G04 ================== begin FILE IDENTIFICATION RECORD ==================*
G04 Layout Name:  9054_F0T_PDB_BD_GPU_F_V04_1213_1550.brd*
G04 Film Name:    smb*
G04 File Format:  Gerber RS274X*
G04 File Origin:  Cadence Allegro 17.2-S081*
G04 Origin Date:  Wed Dec 28 10:19:02 2022*
G04 *
G04 Layer:  DRAWING FORMAT/TITLE_BLOCK_A*
G04 Layer:  DRAWING FORMAT/TITLE_BLOCK*
G04 Layer:  VIA CLASS/SOLDERMASK_BOTTOM*
G04 Layer:  PIN/SOLDERMASK_BOTTOM*
G04 Layer:  PACKAGE GEOMETRY/SOLDERMASK_BOTTOM*
G04 Layer:  MANUFACTURING/PHOTOPLOT_OUTLINE*
G04 Layer:  DRAWING FORMAT/TITLE_DATA_SMB*
G04 Layer:  BOARD GEOMETRY/SOLDERMASK_BOTTOM*
G04 *
G04 Offset:    (0.00 0.00)*
G04 Mirror:    No*
G04 Mode:      Positive*
G04 Rotation:  0*
G04 FullContactRelief:  No*
G04 UndefLineWidth:     6.00*
G04 ================== end FILE IDENTIFICATION RECORD ====================*
%FSLAX25Y25*MOIN*%
%IR0*IPPOS*OFA0.00000B0.00000*MIA0B0*SFA1.00000B1.00000*%
%AMMACRO38*
4,1,5,-.07385,.1083,
-.07385,-.09335,
-.0589,-.1083,
.07385,-.1083,
.07385,.1083,
-.07385,.1083,
0.0*
%
%ADD38MACRO38*%
%ADD15C,.03*%
%ADD32C,.024*%
%ADD61C,.07*%
%ADD12C,.034*%
%ADD68O,.127X.078*%
%ADD51R,.063X.138*%
%ADD69C,.065*%
%ADD18C,.074*%
%ADD54R,.134X.099*%
%ADD46C,.085*%
%ADD60R,.07X.07*%
%ADD56C,.06415*%
%ADD19R,.074X.074*%
%ADD16C,.04952*%
%ADD59R,.06415X.06415*%
%AMMACRO29*
4,1,28,-.00589,.01192,
-.006913,.011842,
-.007907,.011587,
-.008842,.011163,
-.009688,.010584,
-.010422,.009866,
-.011019,.009032,
-.011463,.008107,
-.011739,.007119,
-.01184,.006097,
-.01184,.00603,
-.01184,-.00148,
-.00948,-.00148,
-.00948,-.01191,
.00948,-.01191,
.00948,-.00148,
.01184,-.00148,
.01184,.00603,
.011751,.007052,
.011486,.008044,
.011053,.008974,
.010465,.009815,
.00974,.010541,
.0089,.01113,
.00797,.011564,
.006979,.01183,
.005957,.01192,
.00589,.01192,
-.00589,.01192,
0.0*
%
%ADD29MACRO29*%
%AMMACRO45*
4,1,28,.01192,.00589,
.011842,.006913,
.011587,.007907,
.011163,.008842,
.010584,.009688,
.009866,.010422,
.009032,.011019,
.008107,.011463,
.007119,.011739,
.006097,.01184,
.00603,.01184,
-.00148,.01184,
-.00148,.00948,
-.01191,.00948,
-.01191,-.00948,
-.00148,-.00948,
-.00148,-.01184,
.00603,-.01184,
.007052,-.011751,
.008044,-.011486,
.008974,-.011053,
.009815,-.010465,
.010541,-.00974,
.01113,-.0089,
.011564,-.00797,
.01183,-.006979,
.01192,-.005957,
.01192,-.00589,
.01192,.00589,
0.0*
%
%ADD45MACRO45*%
%ADD17R,.04952X.04952*%
%AMMACRO28*
4,1,28,.0059,-.01191,
.006923,-.01183,
.007916,-.011573,
.00885,-.011148,
.009696,-.010567,
.010428,-.009849,
.011024,-.009013,
.011466,-.008088,
.011741,-.007099,
.01184,-.006078,
.01184,-.00602,
.01184,.00149,
.00948,.00149,
.00948,.01192,
-.00948,.01192,
-.00948,.00149,
-.01184,.00149,
-.01184,-.00602,
-.011751,-.007042,
-.011486,-.008033,
-.011053,-.008964,
-.010465,-.009805,
-.00974,-.010531,
-.0089,-.01112,
-.007971,-.011554,
-.00698,-.01182,
-.005958,-.01191,
-.0059,-.01191,
.0059,-.01191,
0.0*
%
%ADD28MACRO28*%
%AMMACRO44*
4,1,28,-.01191,-.0059,
-.01183,-.006923,
-.011573,-.007916,
-.011148,-.00885,
-.010567,-.009696,
-.009849,-.010428,
-.009013,-.011024,
-.008088,-.011466,
-.007099,-.011741,
-.006078,-.01184,
-.00602,-.01184,
.00149,-.01184,
.00149,-.00948,
.01192,-.00948,
.01192,.00948,
.00149,.00948,
.00149,.01184,
-.00602,.01184,
-.007042,.011751,
-.008033,.011486,
-.008964,.011053,
-.009805,.010465,
-.010531,.00974,
-.01112,.0089,
-.011554,.007971,
-.01182,.00698,
-.01191,.005958,
-.01191,.0059,
-.01191,-.0059,
0.0*
%
%ADD44MACRO44*%
%ADD48R,.114X.224*%
%ADD31R,.024X.022*%
%ADD39R,.032X.015*%
%ADD49O,.037X.014*%
%ADD40R,.015X.032*%
%ADD64R,.028X.021*%
%ADD50O,.014X.037*%
%ADD42R,.034X.015*%
%ADD21C,.103*%
%ADD65R,.021X.028*%
%ADD53R,.139X.132*%
%ADD41R,.015X.034*%
%ADD24R,.036X.032*%
%AMMACRO63*
4,1,5,.07385,-.1083,
.07385,.09335,
.0589,.1083,
-.07385,.1083,
-.07385,-.1083,
.07385,-.1083,
0.0*
%
%ADD63MACRO63*%
%ADD34R,.05X.019*%
%ADD25R,.032X.036*%
%ADD23C,.105*%
%ADD70C,.106*%
%ADD22C,.115*%
%ADD62R,.036X.026*%
%ADD57C,.26*%
%ADD55R,.066X.05*%
%ADD66R,.063X.018*%
%ADD52R,.044X.054*%
%ADD43R,.05X.066*%
%ADD20C,.145*%
%ADD14C,.118*%
%ADD30R,.038X.036*%
%ADD47R,.067X.044*%
%ADD67C,.418*%
%ADD58C,.319*%
%ADD35R,.058X.048*%
%ADD13C,.178*%
%ADD33R,.048X.058*%
%ADD11O,.359X.556*%
%ADD10O,.398X.674*%
%AMMACRO37*
4,1,28,-.01192,-.00589,
-.011842,-.006913,
-.011587,-.007907,
-.011163,-.008842,
-.010584,-.009688,
-.009866,-.010422,
-.009032,-.011019,
-.008107,-.011463,
-.007119,-.011739,
-.006097,-.01184,
-.00603,-.01184,
.00148,-.01184,
.00148,-.00948,
.01191,-.00948,
.01191,.00948,
.00148,.00948,
.00148,.01184,
-.00603,.01184,
-.007052,.011751,
-.008044,.011486,
-.008974,.011053,
-.009815,.010465,
-.010541,.00974,
-.01113,.0089,
-.011564,.00797,
-.01183,.006979,
-.01192,.005957,
-.01192,.00589,
-.01192,-.00589,
0.0*
%
%ADD37MACRO37*%
%AMMACRO27*
4,1,28,.00589,-.01192,
.006913,-.011842,
.007907,-.011587,
.008842,-.011163,
.009688,-.010584,
.010422,-.009866,
.011019,-.009032,
.011463,-.008107,
.011739,-.007119,
.01184,-.006097,
.01184,-.00603,
.01184,.00148,
.00948,.00148,
.00948,.01191,
-.00948,.01191,
-.00948,.00148,
-.01184,.00148,
-.01184,-.00603,
-.011751,-.007052,
-.011486,-.008044,
-.011053,-.008974,
-.010465,-.009815,
-.00974,-.010541,
-.0089,-.01113,
-.00797,-.011564,
-.006979,-.01183,
-.005957,-.01192,
-.00589,-.01192,
.00589,-.01192,
0.0*
%
%ADD27MACRO27*%
%AMMACRO36*
4,1,28,.01191,.0059,
.01183,.006923,
.011573,.007916,
.011148,.00885,
.010567,.009696,
.009849,.010428,
.009013,.011024,
.008088,.011466,
.007099,.011741,
.006078,.01184,
.00602,.01184,
-.00149,.01184,
-.00149,.00948,
-.01192,.00948,
-.01192,-.00948,
-.00149,-.00948,
-.00149,-.01184,
.00602,-.01184,
.007042,-.011751,
.008033,-.011486,
.008964,-.011053,
.009805,-.010465,
.010531,-.00974,
.01112,-.0089,
.011554,-.007971,
.01182,-.00698,
.01191,-.005958,
.01191,-.0059,
.01191,.0059,
0.0*
%
%ADD36MACRO36*%
%AMMACRO26*
4,1,28,-.0059,.01191,
-.006923,.01183,
-.007916,.011573,
-.00885,.011148,
-.009696,.010567,
-.010428,.009849,
-.011024,.009013,
-.011466,.008088,
-.011741,.007099,
-.01184,.006078,
-.01184,.00602,
-.01184,-.00149,
-.00948,-.00149,
-.00948,-.01192,
.00948,-.01192,
.00948,-.00149,
.01184,-.00149,
.01184,.00602,
.011751,.007042,
.011486,.008033,
.011053,.008964,
.010465,.009805,
.00974,.010531,
.0089,.01112,
.007971,.011554,
.00698,.01182,
.005958,.01191,
.0059,.01191,
-.0059,.01191,
0.0*
%
%ADD26MACRO26*%
%ADD71C,.02*%
%ADD72C,.006*%
%ADD73C,.1942*%
G75*
%LPD*%
G75*
G36*
G01X78955Y236614D02*
G02I-19900J0D01*
G37*
G36*
G01Y411594D02*
G02I-19900J0D01*
G37*
G36*
G01X108322Y604336D02*
G03I-5900J0D01*
G37*
G36*
G01X595900Y208500D02*
G03I-5900J0D01*
G37*
G36*
G01X1292200Y331400D02*
G03I-5900J0D01*
G37*
G36*
G01X1693128Y236614D02*
G02I-19900J0D01*
G37*
G36*
G01Y411614D02*
G02I-19900J0D01*
G37*
G36*
G01X1723650Y599624D02*
G03I-5900J0D01*
G37*
%LPC*%
G75*
G54D73*
X59055Y236614D03*
Y411594D03*
X1673228Y236614D03*
Y411614D03*
%LPD*%
G75*
G54D10*
X32284Y555118D03*
X59055Y511811D03*
X1673228D03*
X1700000Y555118D03*
G54D11*
X47244Y27558D03*
Y340550D03*
X279528Y62990D03*
X314961Y570865D03*
X393702Y354330D03*
X748032Y74803D03*
Y354330D03*
X984252Y74803D03*
Y354330D03*
X1338584D03*
X1417324Y570865D03*
X1452756Y62991D03*
X1685040Y27558D03*
Y340550D03*
X1799212Y106299D03*
Y488188D03*
G54D20*
X231600Y81000D03*
X1212478Y300181D03*
X1529100Y78500D03*
G54D30*
X428100Y178900D03*
Y170300D03*
Y223300D03*
Y214700D03*
X1334100Y158800D03*
Y150200D03*
Y203200D03*
Y194600D03*
G54D21*
X207874Y639095D03*
X1524409D03*
G54D12*
X45275Y236614D03*
Y411594D03*
X72835Y236614D03*
X68898Y226771D03*
X59055Y222834D03*
X49212Y226771D03*
X68898Y246457D03*
X49212D03*
X59055Y250394D03*
X68898Y421437D03*
X72835Y411594D03*
X68898Y401751D03*
X59055Y397814D03*
X49212Y401751D03*
Y421437D03*
X59055Y425374D03*
X1673228Y222834D03*
X1663385Y226771D03*
X1659448Y236614D03*
X1663385Y246457D03*
X1673228Y250394D03*
Y397834D03*
X1663385Y401771D03*
X1659448Y411614D03*
X1663385Y421457D03*
X1673228Y425394D03*
X1687008Y236614D03*
X1683071Y226771D03*
Y246457D03*
Y421457D03*
X1687008Y411614D03*
X1683071Y401771D03*
G54D13*
X59055Y236614D03*
Y411594D03*
X1673228Y236614D03*
Y411614D03*
G54D22*
X240866Y15512D03*
X300866Y10197D03*
X1431417Y15512D03*
X1491417Y10197D03*
G54D40*
X595857Y262514D03*
X617511D03*
Y289486D03*
X595857D03*
X1144773Y262514D03*
Y289486D03*
X1166427Y262514D03*
Y289486D03*
G54D31*
X422000Y169925D03*
Y173075D03*
Y214425D03*
Y217575D03*
X1340100Y150125D03*
Y153275D03*
X1340600Y194325D03*
Y197475D03*
G54D14*
X102422Y604336D03*
X590000Y208500D03*
X1286300Y331400D03*
X1717750Y599624D03*
G54D23*
X287402Y628465D03*
X263780Y659961D03*
X1468504Y628465D03*
X1444882Y659961D03*
G54D41*
X603731Y262614D03*
X605700D03*
X607668D03*
X609637D03*
X611605D03*
X613574D03*
X615542D03*
Y289386D03*
X613574D03*
X611605D03*
X609637D03*
X607668D03*
X605700D03*
X603731D03*
X1146742Y262614D03*
X1148710D03*
X1150679D03*
X1152647D03*
X1154616D03*
X1156584D03*
X1158553D03*
Y289386D03*
X1156584D03*
X1154616D03*
X1152647D03*
X1150679D03*
X1148710D03*
X1146742D03*
G54D50*
X709514Y264420D03*
X707544D03*
X705574D03*
X703604D03*
X697704D03*
X695734D03*
X693764D03*
X691794D03*
X689824D03*
X687854D03*
X685884D03*
Y291580D03*
X687854D03*
X689824D03*
X691794D03*
X693764D03*
X695734D03*
X697704D03*
X703604D03*
X705574D03*
X707544D03*
X709514D03*
X711484Y264420D03*
Y291580D03*
X1072460Y260420D03*
X1070490D03*
X1068520D03*
X1066550D03*
X1064580D03*
X1058680D03*
X1056710D03*
X1054740D03*
X1052770D03*
X1050800D03*
Y287580D03*
X1052770D03*
X1054740D03*
X1056710D03*
X1058680D03*
X1064580D03*
X1066550D03*
X1068520D03*
X1070490D03*
X1072460D03*
X1076400Y260420D03*
X1074430D03*
Y287580D03*
X1076400D03*
G54D32*
X561155Y160784D03*
X649200Y254500D03*
X770700Y206900D03*
X776000Y206600D03*
X954200Y200200D03*
X954600Y207200D03*
X1112000Y296000D03*
X1187700Y132400D03*
X1197425Y160284D03*
X1199100Y133300D03*
G54D33*
X601340Y235000D03*
X593860D03*
X664924Y233500D03*
X657444D03*
X720444Y305000D03*
X727924D03*
X1041840Y247000D03*
X1034360D03*
X1074260Y360500D03*
X1096860Y312000D03*
X1104340D03*
X1081740Y360500D03*
X1166860Y312000D03*
X1174340D03*
X1166860Y303000D03*
X1174340D03*
G54D24*
X406600Y169500D03*
Y214000D03*
X412400Y169500D03*
X415200Y180100D03*
X421000D03*
X412400Y214000D03*
X415200Y224500D03*
X421000D03*
X640284Y303500D03*
X646084D03*
X671084Y274000D03*
X665284D03*
X710000Y203000D03*
X704200D03*
X1023200Y203500D03*
X1029000D03*
X1091200Y278000D03*
X1097000D03*
X1122000Y248500D03*
X1116200D03*
X1341200Y160300D03*
Y204400D03*
X1347000Y160300D03*
X1349600Y149500D03*
X1355400D03*
X1347000Y204400D03*
X1349600Y194000D03*
X1355400D03*
G54D42*
X620070Y267142D03*
Y269110D03*
X593298D03*
Y267142D03*
X620070Y271079D03*
Y273047D03*
Y275016D03*
Y276984D03*
Y278953D03*
Y280921D03*
Y282890D03*
Y284858D03*
X593298D03*
Y282890D03*
Y280921D03*
Y278953D03*
Y276984D03*
X1142214Y269110D03*
Y267142D03*
Y284858D03*
Y282890D03*
Y280921D03*
Y278953D03*
Y276984D03*
Y275016D03*
Y273047D03*
Y271079D03*
X1168986Y267142D03*
Y269110D03*
Y271079D03*
Y273047D03*
Y275016D03*
Y282890D03*
Y284858D03*
G54D60*
X825900Y362200D03*
X866400Y382200D03*
X906900Y362200D03*
G54D51*
X704794Y278000D03*
X1057490Y274000D03*
G54D15*
X137355Y120500D03*
X134600Y150000D03*
Y134000D03*
X156785Y101285D03*
X205061Y67500D03*
X211425Y106075D03*
X205061Y93000D03*
X200600Y109059D03*
X210925Y115575D03*
X317000Y58000D03*
X321500Y66500D03*
X332500Y63300D03*
X396216Y46875D03*
X412000Y175000D03*
X417300Y185200D03*
X418500Y229600D03*
X412000Y219300D03*
X441938Y132100D03*
Y309700D03*
X458946Y341216D03*
X455946Y357216D03*
X465946Y357016D03*
X471946Y341216D03*
X484446D03*
X517409Y322000D03*
X506309Y329000D03*
Y322000D03*
X517410Y329000D03*
X551430Y132400D03*
X580184Y117800D03*
X586184Y111800D03*
X580184Y105800D03*
X562830Y140300D03*
X574230Y132400D03*
X563007Y251677D03*
X581562Y272005D03*
X562830Y266500D03*
X571542Y289065D03*
X577808Y278085D03*
X594000Y257000D03*
X602200Y253200D03*
X622003Y297500D03*
X641500Y232000D03*
X626026Y266657D03*
X629684Y260000D03*
X630684Y269000D03*
X627184Y287500D03*
X629684Y300000D03*
X627684Y293425D03*
X635600Y309416D03*
X657784Y40500D03*
Y96000D03*
X676638Y230894D03*
X666000Y241000D03*
X681684Y230820D03*
X676756Y257572D03*
X677184Y267000D03*
X680100Y297600D03*
X672242Y294442D03*
X673800Y289400D03*
X672200Y283700D03*
X675100Y304500D03*
X702223Y197419D03*
X689684Y230762D03*
X698497Y257727D03*
X707980Y252376D03*
X713184Y298500D03*
X695734Y296950D03*
X687854Y299000D03*
X720100Y185000D03*
X725000Y292500D03*
X721214Y284666D03*
X758600Y185000D03*
X788100Y383000D03*
X882660Y350840D03*
X885100Y361500D03*
X974500Y185000D03*
X978600Y310955D03*
X1013000Y185000D03*
X1034360Y254000D03*
X1041840Y253760D03*
X1040539Y266826D03*
X1045337Y298773D03*
X1021414Y355979D03*
X1017300Y385600D03*
X1041400Y368600D03*
X1074500Y43500D03*
Y99000D03*
X1066550Y255050D03*
X1072286Y294922D03*
X1064032Y294958D03*
X1050500Y336500D03*
X1078100Y253500D03*
X1082850Y256750D03*
X1086850Y265750D03*
X1087100Y260500D03*
X1089937Y271255D03*
X1077300Y294000D03*
X1085100Y285000D03*
X1090500Y290500D03*
X1085528Y294428D03*
X1101200Y355600D03*
X1131700Y263000D03*
X1127100Y242500D03*
X1132600Y252000D03*
X1134600Y258575D03*
X1136258Y285343D03*
X1132600Y292000D03*
X1133459Y277272D03*
X1131600Y283000D03*
X1120000Y317500D03*
Y323000D03*
X1113000Y339000D03*
X1133000Y353240D03*
X1140100Y254500D03*
X1160200Y299800D03*
X1152647Y294655D03*
X1166000Y352500D03*
X1182100Y105800D03*
X1167371Y296240D03*
X1182409Y286245D03*
X1180808Y297945D03*
X1176000Y350000D03*
X1168500Y344425D03*
X1210500Y132400D03*
Y265600D03*
X1225930Y359148D03*
X1244874Y330000D03*
X1255975D03*
X1242930Y359148D03*
X1255975Y337000D03*
X1260340Y359284D03*
X1286113Y378312D03*
X1320346Y112300D03*
X1345500Y165500D03*
X1342900Y209600D03*
X1320346Y289900D03*
X1350000Y154800D03*
X1350100Y199250D03*
X1406230Y15076D03*
X1400230Y21076D03*
X1412230D03*
X1494000Y59500D03*
X1490000Y80500D03*
X1499228Y74500D03*
X1490228Y66500D03*
X1505100Y64500D03*
X1551000Y96500D03*
X1567500Y67000D03*
X1618800Y76700D03*
X1597100Y145000D03*
Y126000D03*
X1625370Y103940D03*
X1632336Y109117D03*
X1631323Y115140D03*
X1636400Y127429D03*
X1641932Y122969D03*
X1643217Y135054D03*
X1635000Y142500D03*
X1634500Y147500D03*
X1647500Y140000D03*
X1635000Y152925D03*
X1650117Y180000D03*
X1622100Y155931D03*
X1630075Y158000D03*
X1641500Y178000D03*
X1635000Y164500D03*
X1657050Y116760D03*
X1669800Y120400D03*
X1675800D03*
X1656657Y127365D03*
X1651325Y125076D03*
X1673000Y141000D03*
Y146500D03*
X1676350Y160251D03*
X1673250Y151750D03*
X1674500Y175000D03*
X1680000D03*
X1666500Y178500D03*
X1677000Y169500D03*
X1680500Y165000D03*
X1661000Y178500D03*
X1672050Y181550D03*
X1668075Y189500D03*
X1679176Y194760D03*
X1664000Y202500D03*
X1658500Y183000D03*
X1652500Y185000D03*
X1677500Y182000D03*
X1654000Y192500D03*
X1660000Y193500D03*
X1706100Y92000D03*
X1701350Y114250D03*
X1696600Y119000D03*
X1685100Y127500D03*
X1702525Y129500D03*
X1692600Y135975D03*
X1688100Y145560D03*
X1685000Y133000D03*
X1685976Y153500D03*
X1688100Y173060D03*
Y162060D03*
X1709600Y158000D03*
X1682000Y160000D03*
X1701100Y182000D03*
X1688100Y184220D03*
X1702075Y205500D03*
X1719075Y107016D03*
X1721685Y95940D03*
X1727200Y104500D03*
X1721000Y142525D03*
X1714100Y144925D03*
X1729411Y143661D03*
X1727100Y164280D03*
X1715525Y168500D03*
X1722063Y156962D03*
X1726099Y153000D03*
X1720100Y179500D03*
X1729411Y159161D03*
X1733500Y173760D03*
X1738740Y191500D03*
X1759600Y114500D03*
X1767425Y107000D03*
X1761600Y124524D03*
X1764000Y142525D03*
X1770575Y137000D03*
X1763075Y178900D03*
X1767075Y155484D03*
X1769476Y168500D03*
X1743500Y181000D03*
X1742500Y198000D03*
X1747925Y204000D03*
X1743500Y187500D03*
X1762454Y320347D03*
X1769300Y329400D03*
X1747235Y355989D03*
X1769300Y340600D03*
X1769692Y334649D03*
X1767700Y346200D03*
X1747235Y363689D03*
Y371389D03*
X1773000Y142525D03*
X1773500Y129500D03*
X1773000Y158000D03*
X1772600Y177300D03*
X1795600Y308000D03*
X1817500Y188000D03*
X1811500Y186000D03*
X1847164Y419238D03*
X1842164Y432338D03*
X1847164Y430568D03*
X1852164Y435538D03*
X1837164Y428238D03*
G54D43*
X606484Y312500D03*
X594884D03*
X623384Y231000D03*
X634984D03*
X695800Y242000D03*
X707400D03*
X1127300Y321000D03*
X1155800Y239500D03*
X1138900Y321000D03*
X1167400Y239500D03*
G54D52*
X706184Y305000D03*
X713184D03*
X1056100Y247000D03*
X1049100D03*
X1629737Y96334D03*
X1636737D03*
G54D70*
X1851457Y220433D03*
X1856772Y360433D03*
G54D25*
X417000Y164900D03*
Y159100D03*
X417500Y169600D03*
Y175400D03*
Y208900D03*
Y203100D03*
Y213600D03*
Y219400D03*
X607684Y239950D03*
Y234050D03*
X1107000Y355600D03*
Y361400D03*
X1154600Y312050D03*
Y317950D03*
X1345000Y144900D03*
Y139100D03*
X1344800Y149800D03*
Y155600D03*
X1344500Y188900D03*
Y183100D03*
X1344800Y193700D03*
Y199500D03*
G54D34*
X616666Y239161D03*
Y246839D03*
Y244280D03*
Y241720D03*
X640702Y239161D03*
Y246839D03*
Y244280D03*
Y241720D03*
X1121582Y305161D03*
Y307720D03*
Y310280D03*
Y312839D03*
X1145618Y305161D03*
Y307720D03*
Y310280D03*
Y312839D03*
G54D16*
X137303Y601693D03*
Y609567D03*
Y617441D03*
Y625315D03*
Y633189D03*
Y641063D03*
Y648937D03*
Y656811D03*
X163878Y601693D03*
X156004D03*
X145177D03*
X163878Y609567D03*
Y617441D03*
Y625315D03*
Y633189D03*
X156004Y609567D03*
Y617441D03*
Y625315D03*
Y633189D03*
X145177Y609567D03*
Y617441D03*
Y625315D03*
Y633189D03*
X163878Y641063D03*
Y648937D03*
Y656811D03*
X156004Y641063D03*
Y648937D03*
Y656811D03*
X145177Y641063D03*
Y648937D03*
Y656811D03*
X163878Y664685D03*
X156004D03*
X145177D03*
X192126Y633189D03*
Y625315D03*
Y617441D03*
Y656811D03*
Y648937D03*
Y664685D03*
X200000Y633189D03*
Y625315D03*
Y617441D03*
X215748Y633189D03*
Y625315D03*
Y617441D03*
X223622Y633189D03*
Y625315D03*
X215748Y656811D03*
Y648937D03*
X223622Y656811D03*
Y648937D03*
X200000Y656811D03*
Y648937D03*
X215748Y664685D03*
X223622D03*
X200000D03*
X250866Y20827D03*
Y10197D03*
X255906Y617441D03*
X248032D03*
X255906Y625315D03*
Y633189D03*
X248032D03*
Y625315D03*
X255906Y648937D03*
X248032D03*
X255906Y656811D03*
X248032D03*
X255906Y664685D03*
X248032D03*
X279646Y23012D03*
Y13012D03*
X284646Y18012D03*
X274646D03*
X284646Y8012D03*
X260866Y20827D03*
Y10197D03*
X279528Y617441D03*
X271654D03*
X279528Y625315D03*
Y633189D03*
X271654D03*
Y625315D03*
X279528Y648937D03*
X271654D03*
X279528Y656811D03*
X271654D03*
X279528Y664685D03*
X271654D03*
X289646Y23012D03*
Y13012D03*
X295276Y617441D03*
Y625315D03*
Y633189D03*
X303150D03*
Y625315D03*
Y648937D03*
X295276D03*
X303150Y656811D03*
X295276D03*
X303150Y664685D03*
X295276D03*
X1437008Y617441D03*
X1429134D03*
X1437008Y625315D03*
Y633189D03*
X1429134D03*
Y625315D03*
X1437008Y648937D03*
X1429134D03*
X1437008Y656811D03*
X1429134D03*
X1437008Y664685D03*
X1429134D03*
X1465197Y18012D03*
X1451417Y20827D03*
X1441417D03*
X1451417Y10197D03*
X1441417D03*
X1460630Y617441D03*
X1452756D03*
X1460630Y625315D03*
Y633189D03*
X1452756D03*
Y625315D03*
X1460630Y648937D03*
X1452756D03*
X1460630Y656811D03*
X1452756D03*
X1460630Y664685D03*
X1452756D03*
X1480197Y23012D03*
X1470197D03*
X1480197Y13012D03*
X1470197D03*
X1475197Y18012D03*
Y8012D03*
X1476378Y617441D03*
Y625315D03*
Y633189D03*
X1484252D03*
Y625315D03*
Y648937D03*
X1476378D03*
X1484252Y656811D03*
X1476378D03*
X1484252Y664685D03*
X1476378D03*
X1508661Y633189D03*
Y625315D03*
Y617441D03*
X1516535Y633189D03*
Y625315D03*
Y617441D03*
X1508661Y656811D03*
Y648937D03*
X1516535Y656811D03*
Y648937D03*
X1508661Y664685D03*
X1516535D03*
X1532283Y633189D03*
Y625315D03*
Y617441D03*
X1540157Y633189D03*
Y625315D03*
X1532283Y656811D03*
Y648937D03*
X1540157Y656811D03*
Y648937D03*
X1532283Y664685D03*
X1540157D03*
X1587107Y601693D03*
X1576280D03*
X1568406D03*
X1587107Y609567D03*
Y617441D03*
Y625315D03*
Y633189D03*
X1576280Y609567D03*
Y617441D03*
Y625315D03*
Y633189D03*
X1568406Y609567D03*
Y617441D03*
Y625315D03*
Y633189D03*
X1587107Y641063D03*
Y648937D03*
Y656811D03*
X1576280Y641063D03*
Y648937D03*
Y656811D03*
X1568406Y641063D03*
Y648937D03*
Y656811D03*
X1587107Y664685D03*
X1576280D03*
X1594981Y601693D03*
Y609567D03*
Y617441D03*
Y625315D03*
Y633189D03*
Y641063D03*
Y648937D03*
Y656811D03*
Y664685D03*
G54D61*
X825900Y382200D03*
Y372200D03*
X866400Y362200D03*
Y372200D03*
X906900Y382200D03*
Y372200D03*
G54D71*
G01X0Y603543D02*
Y19685D01*
G01D02*
G03X19685Y0I19685J0D01*
G01Y623228D02*
G03X0Y603543I0J-19685D01*
G01X19685Y0D02*
X1712598D01*
G01X102362Y623228D02*
X19685D01*
G01X122047Y642913D02*
G02X102362Y623228I-19685J0D01*
G01X141732Y675787D02*
G03X122047Y656102I0J-19685D01*
G01D02*
Y642913D01*
G01X295276Y675787D02*
X141732D01*
G01X326772Y623228D02*
G02X314961Y635039I0J11811D01*
G01D02*
Y656102D01*
G01D02*
G03X295276Y675787I-19685J0D01*
G01X348425Y603543D02*
G03X328740Y623228I-19685J0D01*
G01D02*
X326772D01*
G01X1354331Y405512D02*
X377953D01*
G01D02*
G02X348425Y435039I-1J29528D01*
G01D02*
Y603543D01*
G01X1383858Y435039D02*
G02X1354331Y405512I-29527J0D01*
G01X1383858Y603543D02*
Y435039D01*
G01X1417323Y635039D02*
G02X1405512Y623228I-11811J0D01*
G01D02*
X1403543D01*
G01D02*
G03X1383858Y603543I0J-19685D01*
G01X1437008Y675787D02*
G03X1417323Y656102I0J-19685D01*
G01D02*
Y635039D01*
G01X1590551Y675787D02*
X1437008D01*
G01X1629921Y623228D02*
G02X1610236Y642913I0J19685D01*
G01D02*
Y656102D01*
G01D02*
G03X1590551Y675787I-19685J0D01*
G01X1712598Y623228D02*
X1629921D01*
G01X1712598Y0D02*
G03X1732283Y19685I0J19685D01*
G01D02*
Y46339D01*
G01D02*
G02X1751969Y66024I19685J-1D01*
G01Y518780D02*
G02X1732283Y538465I0J19685D01*
G01D02*
Y603543D01*
G01D02*
G03X1712598Y623228I-19685J0D01*
G01X1751969Y66024D02*
X1854331D01*
G01Y518780D02*
X1751969D01*
G01X1854331Y66024D02*
G03X1874016Y85709I0J19685D01*
G01Y499094D02*
G03X1854331Y518780I-19685J1D01*
G01X1874016Y85709D02*
Y499094D01*
G54D26*
X438100Y176084D03*
X612684Y313984D03*
X616684D03*
X635184Y296484D03*
Y304484D03*
X622184Y305484D03*
X1062600Y302484D03*
X1082100D03*
X1074100D03*
X1086100D03*
X1078100D03*
X1090100D03*
X1127100Y274484D03*
X1112500Y361984D03*
X1149600Y249484D03*
X1145600D03*
X1154600Y302484D03*
X1135000Y363984D03*
X1139000D03*
X1176000Y356484D03*
X1170500D03*
X1324100Y156484D03*
X1641077Y130488D03*
G54D35*
X594600Y251240D03*
Y243760D03*
X665684Y224240D03*
Y216760D03*
X673684Y224240D03*
Y216760D03*
X681684Y224240D03*
Y216760D03*
X708600Y196740D03*
Y189260D03*
X689684Y224240D03*
Y216760D03*
X690184Y312760D03*
Y320240D03*
X699184Y312760D03*
Y320240D03*
X1024600Y197240D03*
Y189760D03*
X1063100Y239240D03*
Y231760D03*
X1072100Y239240D03*
Y231760D03*
X1072600Y327760D03*
X1064600D03*
X1072600Y335240D03*
X1064600D03*
X1088100Y327760D03*
X1080600D03*
X1088100Y335240D03*
X1080600D03*
X1113000Y353240D03*
Y345760D03*
G54D62*
X1128224Y358760D03*
X1118776D03*
X1128224Y366240D03*
X1118776D03*
Y362500D03*
X1758824Y183760D03*
Y191240D03*
X1749376D03*
Y187500D03*
Y183760D03*
G54D53*
X739600Y140094D03*
Y176906D03*
X994000Y140094D03*
Y176906D03*
G54D44*
X635200Y269000D03*
Y264500D03*
Y260000D03*
Y273500D03*
Y288500D03*
X663200Y262500D03*
Y254500D03*
X661200Y267000D03*
X663200Y258500D03*
X664616Y304500D03*
Y300500D03*
X707516Y208000D03*
X688700Y306500D03*
X1024616Y212500D03*
X1061616Y245500D03*
X1066116Y250000D03*
X1067116Y301000D03*
X1094616Y259500D03*
Y255500D03*
Y267500D03*
Y263500D03*
Y243500D03*
Y271500D03*
X1090616Y283000D03*
X1117616Y243500D03*
X1124116Y267500D03*
X1119616Y258500D03*
Y254000D03*
X1120116Y274500D03*
X1131116Y270000D03*
X1154116Y249500D03*
X1154616Y306500D03*
X1162516Y338000D03*
X1627016Y139000D03*
Y149500D03*
X1652516Y138000D03*
X1678016Y141500D03*
Y145500D03*
Y153500D03*
G54D17*
X137303Y664685D03*
X223622Y617441D03*
X274646Y8012D03*
X303150Y617441D03*
X1465197Y8012D03*
X1484252Y617441D03*
X1540157D03*
X1568406Y664685D03*
G54D72*
G01X-457143Y-1211429D02*
Y2242857D01*
X4308572D01*
Y-1211429D01*
X-457143D01*
G01X37000Y-995000D02*
Y-1070000D01*
X537000D01*
Y-995000D01*
X37000D01*
G01X49000Y-1060000D02*
Y-1065000D01*
G01X47543Y-1060000D02*
X50457D01*
G01X55367Y-1065000D02*
X52833D01*
Y-1060000D01*
X55367D01*
G01X54353Y-1062417D02*
X52833D01*
G01X57933Y-1060000D02*
Y-1065000D01*
X60467D01*
G01X64300Y-1065167D02*
X64173Y-1065083D01*
Y-1064917D01*
X64300Y-1064833D01*
X64427Y-1064917D01*
Y-1065083D01*
X64300Y-1065167D01*
G01Y-1062917D02*
X64173Y-1062833D01*
Y-1062667D01*
X64300Y-1062583D01*
X64427Y-1062667D01*
Y-1062833D01*
X64300Y-1062917D01*
G01X69083Y-1066667D02*
X68450Y-1065833D01*
X68133Y-1065000D01*
Y-1061667D01*
X68450Y-1060833D01*
X69083Y-1060000D01*
G01X74500D02*
X73993Y-1060167D01*
X73613Y-1060583D01*
X73360Y-1061083D01*
X73170Y-1061750D01*
X73107Y-1062500D01*
X73170Y-1063250D01*
X73360Y-1063917D01*
X73613Y-1064417D01*
X73993Y-1064833D01*
X74500Y-1065000D01*
X75007Y-1064833D01*
X75387Y-1064417D01*
X75640Y-1063917D01*
X75830Y-1063250D01*
X75893Y-1062500D01*
X75830Y-1061750D01*
X75640Y-1061083D01*
X75387Y-1060583D01*
X75007Y-1060167D01*
X74500Y-1060000D01*
G01X78207Y-1064000D02*
X78587Y-1064583D01*
X79093Y-1064917D01*
X79663Y-1065000D01*
X80170Y-1064917D01*
X80677Y-1064500D01*
X80993Y-1064000D01*
X81057Y-1063500D01*
X80930Y-1062917D01*
X80487Y-1062500D01*
X80043Y-1062333D01*
X79473D01*
G01X80043D02*
X80423Y-1062083D01*
X80740Y-1061667D01*
X80867Y-1061167D01*
X80740Y-1060667D01*
X80423Y-1060250D01*
X79853Y-1060000D01*
X79283Y-1060083D01*
X78713Y-1060417D01*
G01X85017Y-1066667D02*
X85650Y-1065833D01*
X85967Y-1065000D01*
Y-1061667D01*
X85650Y-1060833D01*
X85017Y-1060000D01*
G01X88407Y-1064000D02*
X88787Y-1064583D01*
X89293Y-1064917D01*
X89863Y-1065000D01*
X90370Y-1064917D01*
X90877Y-1064500D01*
X91193Y-1064000D01*
X91257Y-1063500D01*
X91130Y-1062917D01*
X90687Y-1062500D01*
X90243Y-1062333D01*
X89673D01*
G01X90243D02*
X90623Y-1062083D01*
X90940Y-1061667D01*
X91067Y-1061167D01*
X90940Y-1060667D01*
X90623Y-1060250D01*
X90053Y-1060000D01*
X89483Y-1060083D01*
X88913Y-1060417D01*
G01X93697Y-1060833D02*
X94077Y-1060333D01*
X94520Y-1060083D01*
X95027Y-1060000D01*
X95660Y-1060167D01*
X96103Y-1060583D01*
X96230Y-1061083D01*
X96167Y-1061583D01*
X95913Y-1062000D01*
X94647Y-1062833D01*
X94077Y-1063417D01*
X93697Y-1064250D01*
X93570Y-1065000D01*
X96230D01*
G01X99873D02*
X100000Y-1063917D01*
X100190Y-1063000D01*
X100443Y-1062167D01*
X100760Y-1061250D01*
X101267Y-1060000D01*
X98733D01*
G01X104277Y-1063333D02*
X105923D01*
G01X108997Y-1060833D02*
X109377Y-1060333D01*
X109820Y-1060083D01*
X110327Y-1060000D01*
X110960Y-1060167D01*
X111403Y-1060583D01*
X111530Y-1061083D01*
X111467Y-1061583D01*
X111213Y-1062000D01*
X109947Y-1062833D01*
X109377Y-1063417D01*
X108997Y-1064250D01*
X108870Y-1065000D01*
X111530D01*
G01X113907Y-1064000D02*
X114287Y-1064583D01*
X114793Y-1064917D01*
X115363Y-1065000D01*
X115870Y-1064917D01*
X116377Y-1064500D01*
X116693Y-1064000D01*
X116757Y-1063500D01*
X116630Y-1062917D01*
X116187Y-1062500D01*
X115743Y-1062333D01*
X115173D01*
G01X115743D02*
X116123Y-1062083D01*
X116440Y-1061667D01*
X116567Y-1061167D01*
X116440Y-1060667D01*
X116123Y-1060250D01*
X115553Y-1060000D01*
X114983Y-1060083D01*
X114413Y-1060417D01*
G01X121160Y-1065000D02*
Y-1060000D01*
X118817Y-1063583D01*
X121983D01*
G01X124107Y-1064250D02*
X124487Y-1064667D01*
X124930Y-1064917D01*
X125500Y-1065000D01*
X126070Y-1064833D01*
X126513Y-1064500D01*
X126830Y-1063917D01*
X126893Y-1063250D01*
X126767Y-1062583D01*
X126450Y-1062167D01*
X126007Y-1061833D01*
X125563Y-1061750D01*
X125120Y-1061833D01*
X124550Y-1062167D01*
X124740Y-1060000D01*
X126450D01*
G01X134497Y-1065000D02*
Y-1060000D01*
X136903D01*
G01X136017Y-1062417D02*
X134497D01*
G01X139217Y-1065000D02*
X140800Y-1060000D01*
X142383Y-1065000D01*
G01X141813Y-1063250D02*
X139787D01*
G01X144570Y-1065000D02*
X147230Y-1060000D01*
G01X144570D02*
X147230Y-1065000D01*
G01X151000Y-1065167D02*
X150873Y-1065083D01*
Y-1064917D01*
X151000Y-1064833D01*
X151127Y-1064917D01*
Y-1065083D01*
X151000Y-1065167D01*
G01Y-1062917D02*
X150873Y-1062833D01*
Y-1062667D01*
X151000Y-1062583D01*
X151127Y-1062667D01*
Y-1062833D01*
X151000Y-1062917D01*
G01X155783Y-1066667D02*
X155150Y-1065833D01*
X154833Y-1065000D01*
Y-1061667D01*
X155150Y-1060833D01*
X155783Y-1060000D01*
G01X161200D02*
X160693Y-1060167D01*
X160313Y-1060583D01*
X160060Y-1061083D01*
X159870Y-1061750D01*
X159807Y-1062500D01*
X159870Y-1063250D01*
X160060Y-1063917D01*
X160313Y-1064417D01*
X160693Y-1064833D01*
X161200Y-1065000D01*
X161707Y-1064833D01*
X162087Y-1064417D01*
X162340Y-1063917D01*
X162530Y-1063250D01*
X162593Y-1062500D01*
X162530Y-1061750D01*
X162340Y-1061083D01*
X162087Y-1060583D01*
X161707Y-1060167D01*
X161200Y-1060000D01*
G01X164907Y-1064000D02*
X165287Y-1064583D01*
X165793Y-1064917D01*
X166363Y-1065000D01*
X166870Y-1064917D01*
X167377Y-1064500D01*
X167693Y-1064000D01*
X167757Y-1063500D01*
X167630Y-1062917D01*
X167187Y-1062500D01*
X166743Y-1062333D01*
X166173D01*
G01X166743D02*
X167123Y-1062083D01*
X167440Y-1061667D01*
X167567Y-1061167D01*
X167440Y-1060667D01*
X167123Y-1060250D01*
X166553Y-1060000D01*
X165983Y-1060083D01*
X165413Y-1060417D01*
G01X171717Y-1066667D02*
X172350Y-1065833D01*
X172667Y-1065000D01*
Y-1061667D01*
X172350Y-1060833D01*
X171717Y-1060000D01*
G01X175107Y-1064000D02*
X175487Y-1064583D01*
X175993Y-1064917D01*
X176563Y-1065000D01*
X177070Y-1064917D01*
X177577Y-1064500D01*
X177893Y-1064000D01*
X177957Y-1063500D01*
X177830Y-1062917D01*
X177387Y-1062500D01*
X176943Y-1062333D01*
X176373D01*
G01X176943D02*
X177323Y-1062083D01*
X177640Y-1061667D01*
X177767Y-1061167D01*
X177640Y-1060667D01*
X177323Y-1060250D01*
X176753Y-1060000D01*
X176183Y-1060083D01*
X175613Y-1060417D01*
G01X180523Y-1064417D02*
X180967Y-1064833D01*
X181473Y-1065000D01*
X181980Y-1064833D01*
X182423Y-1064333D01*
X182740Y-1063583D01*
X182867Y-1062833D01*
Y-1061917D01*
X182740Y-1061167D01*
X182423Y-1060500D01*
X182043Y-1060167D01*
X181600Y-1060000D01*
X181093Y-1060167D01*
X180713Y-1060500D01*
X180460Y-1061000D01*
X180333Y-1061667D01*
X180460Y-1062250D01*
X180777Y-1062833D01*
X181157Y-1063167D01*
X181600Y-1063250D01*
X182107Y-1063083D01*
X182487Y-1062667D01*
X182867Y-1061917D01*
G01X186573Y-1065000D02*
X186700Y-1063917D01*
X186890Y-1063000D01*
X187143Y-1062167D01*
X187460Y-1061250D01*
X187967Y-1060000D01*
X185433D01*
G01X190977Y-1063333D02*
X192623D01*
G01X195507Y-1064000D02*
X195887Y-1064583D01*
X196393Y-1064917D01*
X196963Y-1065000D01*
X197470Y-1064917D01*
X197977Y-1064500D01*
X198293Y-1064000D01*
X198357Y-1063500D01*
X198230Y-1062917D01*
X197787Y-1062500D01*
X197343Y-1062333D01*
X196773D01*
G01X197343D02*
X197723Y-1062083D01*
X198040Y-1061667D01*
X198167Y-1061167D01*
X198040Y-1060667D01*
X197723Y-1060250D01*
X197153Y-1060000D01*
X196583Y-1060083D01*
X196013Y-1060417D01*
G01X200797Y-1062917D02*
X201240Y-1062333D01*
X201620Y-1062000D01*
X202127Y-1061833D01*
X202570Y-1062000D01*
X202887Y-1062333D01*
X203140Y-1062833D01*
X203203Y-1063417D01*
X203140Y-1063917D01*
X202887Y-1064417D01*
X202507Y-1064833D01*
X202063Y-1065000D01*
X201557Y-1064833D01*
X201113Y-1064333D01*
X200860Y-1063583D01*
X200797Y-1062750D01*
X200923Y-1061667D01*
X201113Y-1061083D01*
X201430Y-1060500D01*
X201873Y-1060083D01*
X202317Y-1060000D01*
X202760Y-1060167D01*
X203077Y-1060583D01*
G01X207100Y-1065000D02*
Y-1060000D01*
X206340Y-1061000D01*
G01Y-1065000D02*
X207860D01*
G01X212960D02*
Y-1060000D01*
X210617Y-1063583D01*
X213783D01*
G01X232000Y-995000D02*
Y-1070000D01*
G01Y-1045000D02*
X335000D01*
Y-1020000D01*
G01X232000D02*
X335000D01*
G01X337000Y-995000D02*
Y-1070000D01*
G01X335000Y-995000D02*
Y-1070000D01*
G01X342507Y-1055000D02*
Y-1050000D01*
X343773D01*
X344280Y-1050250D01*
X344660Y-1050583D01*
X344977Y-1051083D01*
X345230Y-1051667D01*
X345293Y-1052500D01*
X345230Y-1053333D01*
X344977Y-1053917D01*
X344660Y-1054417D01*
X344280Y-1054750D01*
X343773Y-1055000D01*
X342507D01*
G01X347417D02*
X349000Y-1050000D01*
X350583Y-1055000D01*
G01X350013Y-1053250D02*
X347987D01*
G01X354100Y-1050000D02*
Y-1055000D01*
G01X352643Y-1050000D02*
X355557D01*
G01X360467Y-1055000D02*
X357933D01*
Y-1050000D01*
X360467D01*
G01X359453Y-1052417D02*
X357933D01*
G01X364300Y-1055167D02*
X364173Y-1055083D01*
Y-1054917D01*
X364300Y-1054833D01*
X364427Y-1054917D01*
Y-1055083D01*
X364300Y-1055167D01*
G01Y-1052917D02*
X364173Y-1052833D01*
Y-1052667D01*
X364300Y-1052583D01*
X364427Y-1052667D01*
Y-1052833D01*
X364300Y-1052917D01*
G01X337000Y-1045000D02*
X537000D01*
G01X342633Y-1030000D02*
Y-1025000D01*
X344153D01*
X344660Y-1025250D01*
X345040Y-1025833D01*
X345167Y-1026500D01*
X345040Y-1027167D01*
X344723Y-1027667D01*
X344153Y-1027917D01*
X342633D01*
G01X347860Y-1030167D02*
X350140Y-1025000D01*
G01X352643Y-1030000D02*
Y-1025000D01*
X355557Y-1030000D01*
Y-1025000D01*
G01X359200Y-1030167D02*
X359073Y-1030083D01*
Y-1029917D01*
X359200Y-1029833D01*
X359327Y-1029917D01*
Y-1030083D01*
X359200Y-1030167D01*
G01Y-1027917D02*
X359073Y-1027833D01*
Y-1027667D01*
X359200Y-1027583D01*
X359327Y-1027667D01*
Y-1027833D01*
X359200Y-1027917D01*
G01X342633Y-1005000D02*
Y-1000000D01*
X344153D01*
X344660Y-1000250D01*
X345040Y-1000833D01*
X345167Y-1001500D01*
X345040Y-1002167D01*
X344723Y-1002667D01*
X344153Y-1002917D01*
X342633D01*
G01X347733Y-1005000D02*
Y-1000000D01*
X349317D01*
X349823Y-1000250D01*
X350140Y-1000583D01*
X350267Y-1001250D01*
X350140Y-1001917D01*
X349760Y-1002333D01*
X349317Y-1002583D01*
X347733D01*
G01X349317D02*
X350267Y-1005000D01*
G01X354100D02*
X353593Y-1004917D01*
X353150Y-1004583D01*
X352770Y-1004083D01*
X352517Y-1003500D01*
X352390Y-1002833D01*
Y-1002167D01*
X352517Y-1001500D01*
X352770Y-1000917D01*
X353150Y-1000417D01*
X353593Y-1000083D01*
X354100Y-1000000D01*
X354607Y-1000083D01*
X355050Y-1000417D01*
X355430Y-1000917D01*
X355683Y-1001500D01*
X355810Y-1002167D01*
Y-1002833D01*
X355683Y-1003500D01*
X355430Y-1004083D01*
X355050Y-1004583D01*
X354607Y-1004917D01*
X354100Y-1005000D01*
G01X357933Y-1004000D02*
X358250Y-1004500D01*
X358630Y-1004833D01*
X359073Y-1005000D01*
X359580Y-1004833D01*
X359960Y-1004500D01*
X360340Y-1004000D01*
X360467Y-1003333D01*
Y-1000000D01*
G01X365567Y-1005000D02*
X363033D01*
Y-1000000D01*
X365567D01*
G01X364553Y-1002417D02*
X363033D01*
G01X370793Y-1000417D02*
X370413Y-1000167D01*
X369970Y-1000000D01*
X369463D01*
X368893Y-1000250D01*
X368450Y-1000667D01*
X368133Y-1001167D01*
X367880Y-1002000D01*
X367817Y-1002750D01*
X367943Y-1003500D01*
X368133Y-1004000D01*
X368513Y-1004500D01*
X368957Y-1004833D01*
X369400Y-1005000D01*
X369843D01*
X370287Y-1004833D01*
X370667Y-1004583D01*
X370983Y-1004250D01*
G01X374500Y-1000000D02*
Y-1005000D01*
G01X373043Y-1000000D02*
X375957D01*
G01X379600Y-1005167D02*
X379473Y-1005083D01*
Y-1004917D01*
X379600Y-1004833D01*
X379727Y-1004917D01*
Y-1005083D01*
X379600Y-1005167D01*
G01Y-1002917D02*
X379473Y-1002833D01*
Y-1002667D01*
X379600Y-1002583D01*
X379727Y-1002667D01*
Y-1002833D01*
X379600Y-1002917D01*
G01X337000Y-1020000D02*
X537000D01*
G01X452000Y-1045000D02*
Y-1070000D01*
G01X454633Y-1047500D02*
Y-1052500D01*
X457167D01*
G01X460240Y-1047500D02*
X461760D01*
G01X461000D02*
Y-1052500D01*
G01X460240D02*
X461760D01*
G01X466607Y-1049833D02*
X466860Y-1049583D01*
X467050Y-1049167D01*
X467177Y-1048583D01*
X467050Y-1048083D01*
X466797Y-1047750D01*
X466353Y-1047500D01*
X464643D01*
Y-1052500D01*
X466733D01*
X467177Y-1052167D01*
X467430Y-1051667D01*
X467557Y-1051083D01*
X467430Y-1050500D01*
X467050Y-1050000D01*
X466607Y-1049833D01*
X464643D01*
G01X471200Y-1052667D02*
X471073Y-1052583D01*
Y-1052417D01*
X471200Y-1052333D01*
X471327Y-1052417D01*
Y-1052583D01*
X471200Y-1052667D01*
G01Y-1050417D02*
X471073Y-1050333D01*
Y-1050167D01*
X471200Y-1050083D01*
X471327Y-1050167D01*
Y-1050333D01*
X471200Y-1050417D01*
G01X495000Y-1045000D02*
Y-1070000D01*
G01X498900Y-1047500D02*
Y-1052500D01*
G01X497443Y-1047500D02*
X500357D01*
G01X504000Y-1052500D02*
X503620Y-1052417D01*
X503240Y-1052083D01*
X502987Y-1051500D01*
X502860Y-1050833D01*
X502987Y-1050167D01*
X503240Y-1049583D01*
X503620Y-1049250D01*
X504000Y-1049167D01*
X504380Y-1049250D01*
X504760Y-1049583D01*
X505013Y-1050167D01*
X505077Y-1050833D01*
X505013Y-1051500D01*
X504760Y-1052083D01*
X504380Y-1052417D01*
X504000Y-1052500D01*
G01X509100D02*
X508720Y-1052417D01*
X508340Y-1052083D01*
X508087Y-1051500D01*
X507960Y-1050833D01*
X508087Y-1050167D01*
X508340Y-1049583D01*
X508720Y-1049250D01*
X509100Y-1049167D01*
X509480Y-1049250D01*
X509860Y-1049583D01*
X510113Y-1050167D01*
X510177Y-1050833D01*
X510113Y-1051500D01*
X509860Y-1052083D01*
X509480Y-1052417D01*
X509100Y-1052500D01*
G01X514200D02*
Y-1047500D01*
G01X519300Y-1052667D02*
X519173Y-1052583D01*
Y-1052417D01*
X519300Y-1052333D01*
X519427Y-1052417D01*
Y-1052583D01*
X519300Y-1052667D01*
G01Y-1050417D02*
X519173Y-1050333D01*
Y-1050167D01*
X519300Y-1050083D01*
X519427Y-1050167D01*
Y-1050333D01*
X519300Y-1050417D01*
G01X495000Y-1020000D02*
Y-1045000D01*
G01X497633Y-1027500D02*
Y-1022500D01*
X499217D01*
X499723Y-1022750D01*
X500040Y-1023083D01*
X500167Y-1023750D01*
X500040Y-1024417D01*
X499660Y-1024833D01*
X499217Y-1025083D01*
X497633D01*
G01X499217D02*
X500167Y-1027500D01*
G01X505267D02*
X502733D01*
Y-1022500D01*
X505267D01*
G01X504253Y-1024917D02*
X502733D01*
G01X507517Y-1022500D02*
X509100Y-1027500D01*
X510683Y-1022500D01*
G01X514200Y-1027667D02*
X514073Y-1027583D01*
Y-1027417D01*
X514200Y-1027333D01*
X514327Y-1027417D01*
Y-1027583D01*
X514200Y-1027667D01*
G01Y-1025417D02*
X514073Y-1025333D01*
Y-1025167D01*
X514200Y-1025083D01*
X514327Y-1025167D01*
Y-1025333D01*
X514200Y-1025417D01*
G01X503013Y-1073167D02*
X503120Y-1073042D01*
X503200Y-1072833D01*
X503253Y-1072542D01*
X503200Y-1072292D01*
X503093Y-1072125D01*
X502907Y-1072000D01*
X502187D01*
Y-1074500D01*
X503067D01*
X503253Y-1074333D01*
X503360Y-1074083D01*
X503413Y-1073792D01*
X503360Y-1073500D01*
X503200Y-1073250D01*
X503013Y-1073167D01*
X502187D01*
G01X505480Y-1074500D02*
Y-1072833D01*
G01Y-1073125D02*
X505373Y-1072958D01*
X505213Y-1072875D01*
X505027Y-1072833D01*
X504840Y-1072917D01*
X504680Y-1073083D01*
X504573Y-1073333D01*
X504520Y-1073667D01*
X504573Y-1074000D01*
X504680Y-1074250D01*
X504840Y-1074417D01*
X505027Y-1074500D01*
X505213Y-1074458D01*
X505373Y-1074333D01*
X505480Y-1074167D01*
G01X506800Y-1074208D02*
X506933Y-1074375D01*
X507120Y-1074500D01*
X507280D01*
X507440Y-1074417D01*
X507547Y-1074292D01*
X507600Y-1074125D01*
X507573Y-1073875D01*
X507467Y-1073750D01*
X506987Y-1073500D01*
X506880Y-1073208D01*
X506933Y-1073000D01*
X507040Y-1072875D01*
X507200Y-1072833D01*
X507360Y-1072875D01*
X507520Y-1073000D01*
G01X509000Y-1073375D02*
X509853D01*
X509773Y-1073083D01*
X509640Y-1072917D01*
X509453Y-1072833D01*
X509267Y-1072875D01*
X509107Y-1073000D01*
X509000Y-1073292D01*
X508947Y-1073542D01*
Y-1073792D01*
X509000Y-1074042D01*
X509133Y-1074292D01*
X509293Y-1074458D01*
X509480Y-1074500D01*
X509667Y-1074417D01*
X509853Y-1074167D01*
G01X511120Y-1074500D02*
Y-1072000D01*
G01Y-1073250D02*
X511253Y-1073000D01*
X511413Y-1072875D01*
X511573Y-1072833D01*
X511813Y-1072917D01*
X511973Y-1073083D01*
X512080Y-1073375D01*
Y-1073708D01*
X512027Y-1074042D01*
X511920Y-1074292D01*
X511733Y-1074458D01*
X511573Y-1074500D01*
X511413Y-1074458D01*
X511253Y-1074333D01*
X511120Y-1074125D01*
G01X513800Y-1074500D02*
X513640Y-1074458D01*
X513480Y-1074292D01*
X513373Y-1074000D01*
X513320Y-1073667D01*
X513373Y-1073333D01*
X513480Y-1073042D01*
X513640Y-1072875D01*
X513800Y-1072833D01*
X513960Y-1072875D01*
X514120Y-1073042D01*
X514227Y-1073333D01*
X514253Y-1073667D01*
X514227Y-1074000D01*
X514120Y-1074292D01*
X513960Y-1074458D01*
X513800Y-1074500D01*
G01X516480D02*
Y-1072833D01*
G01Y-1073125D02*
X516373Y-1072958D01*
X516213Y-1072875D01*
X516027Y-1072833D01*
X515840Y-1072917D01*
X515680Y-1073083D01*
X515573Y-1073333D01*
X515520Y-1073667D01*
X515573Y-1074000D01*
X515680Y-1074250D01*
X515840Y-1074417D01*
X516027Y-1074500D01*
X516213Y-1074458D01*
X516373Y-1074333D01*
X516480Y-1074167D01*
G01X517827Y-1074500D02*
Y-1072833D01*
G01Y-1073167D02*
X517960Y-1073000D01*
X518093Y-1072875D01*
X518280Y-1072833D01*
X518413Y-1072875D01*
X518573Y-1073000D01*
G01X520880Y-1072000D02*
Y-1074500D01*
G01Y-1074125D02*
X520773Y-1074333D01*
X520613Y-1074458D01*
X520427Y-1074500D01*
X520213Y-1074417D01*
X520053Y-1074208D01*
X519947Y-1073958D01*
X519920Y-1073667D01*
X519947Y-1073375D01*
X520053Y-1073125D01*
X520213Y-1072917D01*
X520427Y-1072833D01*
X520613Y-1072875D01*
X520747Y-1072958D01*
X520880Y-1073125D01*
G01X524267Y-1074500D02*
Y-1072000D01*
X524933D01*
X525147Y-1072125D01*
X525280Y-1072292D01*
X525333Y-1072625D01*
X525280Y-1072958D01*
X525120Y-1073167D01*
X524933Y-1073292D01*
X524267D01*
G01X524933D02*
X525333Y-1074500D01*
G01X526600Y-1073375D02*
X527453D01*
X527373Y-1073083D01*
X527240Y-1072917D01*
X527053Y-1072833D01*
X526867Y-1072875D01*
X526707Y-1073000D01*
X526600Y-1073292D01*
X526547Y-1073542D01*
Y-1073792D01*
X526600Y-1074042D01*
X526733Y-1074292D01*
X526893Y-1074458D01*
X527080Y-1074500D01*
X527267Y-1074417D01*
X527453Y-1074167D01*
G01X528720Y-1072833D02*
X529200Y-1074500D01*
X529680Y-1072833D01*
G01X531400Y-1074583D02*
X531347Y-1074542D01*
Y-1074458D01*
X531400Y-1074417D01*
X531453Y-1074458D01*
Y-1074542D01*
X531400Y-1074583D01*
G01X533600Y-1074500D02*
X533787Y-1074458D01*
X534000Y-1074333D01*
X534133Y-1074125D01*
X534187Y-1073833D01*
X534133Y-1073542D01*
X533973Y-1073292D01*
X533733Y-1073167D01*
X533467D01*
X533307Y-1073083D01*
X533173Y-1072875D01*
X533120Y-1072583D01*
X533200Y-1072292D01*
X533387Y-1072083D01*
X533600Y-1072000D01*
X533813Y-1072083D01*
X534000Y-1072292D01*
X534080Y-1072583D01*
X534027Y-1072875D01*
X533893Y-1073083D01*
X533733Y-1073167D01*
X533467D01*
X533227Y-1073292D01*
X533067Y-1073542D01*
X533013Y-1073833D01*
X533067Y-1074125D01*
X533200Y-1074333D01*
X533413Y-1074458D01*
X533600Y-1074500D01*
G01X536013Y-1073167D02*
X536120Y-1073042D01*
X536200Y-1072833D01*
X536253Y-1072542D01*
X536200Y-1072292D01*
X536093Y-1072125D01*
X535907Y-1072000D01*
X535187D01*
Y-1074500D01*
X536067D01*
X536253Y-1074333D01*
X536360Y-1074083D01*
X536413Y-1073792D01*
X536360Y-1073500D01*
X536200Y-1073250D01*
X536013Y-1073167D01*
X535187D01*
G01X-457143Y-1211429D02*
Y2242857D01*
X4308572D01*
Y-1211429D01*
X-457143D01*
G01X71650Y-1024800D02*
X69130Y-1024383D01*
X66925Y-1022717D01*
X65035Y-1020217D01*
X63775Y-1017300D01*
X63145Y-1013967D01*
Y-1010633D01*
X63775Y-1007300D01*
X65035Y-1004383D01*
X66925Y-1001884D01*
X69130Y-1000217D01*
X71650Y-999800D01*
X74170Y-1000217D01*
X76375Y-1001884D01*
X78265Y-1004383D01*
X79525Y-1007300D01*
X80155Y-1010633D01*
Y-1013967D01*
X79525Y-1017300D01*
X78265Y-1020217D01*
X76375Y-1022717D01*
X74170Y-1024383D01*
X71650Y-1024800D01*
G01X74170Y-1018133D02*
X77950Y-1024800D01*
G01X91495Y-1008134D02*
Y-1019800D01*
X92755Y-1022717D01*
X94645Y-1024383D01*
X96850Y-1024800D01*
X99055Y-1024383D01*
X100945Y-1022717D01*
X102205Y-1019800D01*
G01Y-1024800D02*
Y-1008134D01*
G01X127720Y-1024800D02*
Y-1008134D01*
G01Y-1011050D02*
X126460Y-1009384D01*
X124570Y-1008550D01*
X122365Y-1008134D01*
X120160Y-1008967D01*
X118270Y-1010633D01*
X117010Y-1013134D01*
X116380Y-1016467D01*
X117010Y-1019800D01*
X118270Y-1022301D01*
X120160Y-1023967D01*
X122365Y-1024800D01*
X124570Y-1024383D01*
X126460Y-1023134D01*
X127720Y-1021467D01*
G01X141895Y-1024800D02*
Y-1008134D01*
G01Y-1012300D02*
X143155Y-1010217D01*
X145045Y-1008550D01*
X147565Y-1008134D01*
X149770Y-1008550D01*
X151660Y-1010217D01*
X152605Y-1013134D01*
Y-1024800D01*
G01X172450Y-999800D02*
Y-1024800D01*
G01X168040Y-1008134D02*
X176860D01*
G01X203320Y-1024800D02*
Y-1008134D01*
G01Y-1011050D02*
X202060Y-1009384D01*
X200170Y-1008550D01*
X197965Y-1008134D01*
X195760Y-1008967D01*
X193870Y-1010633D01*
X192610Y-1013134D01*
X191980Y-1016467D01*
X192610Y-1019800D01*
X193870Y-1022301D01*
X195760Y-1023967D01*
X197965Y-1024800D01*
X200170Y-1024383D01*
X202060Y-1023134D01*
X203320Y-1021467D01*
G01X49820Y-1042350D02*
X51387D01*
Y-1044240D01*
X50917Y-1044870D01*
X50368Y-1045290D01*
X49585Y-1045500D01*
X48802Y-1045290D01*
X48253Y-1044870D01*
X47783Y-1044240D01*
X47470Y-1043505D01*
X47313Y-1042665D01*
Y-1041930D01*
X47470Y-1041300D01*
X47783Y-1040565D01*
X48253Y-1039935D01*
X48723Y-1039515D01*
X49350Y-1039200D01*
X49898D01*
X50525Y-1039410D01*
X50995Y-1039830D01*
G01X53927Y-1039200D02*
Y-1043715D01*
X54240Y-1044660D01*
X54867Y-1045290D01*
X55650Y-1045500D01*
X56433Y-1045290D01*
X57060Y-1044660D01*
X57373Y-1043715D01*
Y-1039200D01*
G01X61010D02*
X62890D01*
G01X61950D02*
Y-1045500D01*
G01X61010D02*
X62890D01*
G01X66605Y-1044660D02*
X67232Y-1045185D01*
X67937Y-1045500D01*
X68563D01*
X69190Y-1045185D01*
X69660Y-1044660D01*
X69895Y-1043925D01*
X69738Y-1043190D01*
X69347Y-1042560D01*
X68642Y-1042140D01*
X67702Y-1041930D01*
X67153Y-1041510D01*
X66918Y-1040775D01*
X67075Y-1040040D01*
X67467Y-1039515D01*
X68015Y-1039200D01*
X68563D01*
X69112Y-1039410D01*
X69582Y-1039935D01*
G01X72905Y-1045500D02*
Y-1039200D01*
G01X76195D02*
Y-1045500D01*
G01Y-1042350D02*
X72905D01*
G01X78892Y-1045500D02*
X80850Y-1039200D01*
X82808Y-1045500D01*
G01X82103Y-1043295D02*
X79597D01*
G01X85348Y-1045500D02*
Y-1039200D01*
X88952Y-1045500D01*
Y-1039200D01*
G01X98027Y-1045500D02*
Y-1039200D01*
X99593D01*
X100220Y-1039515D01*
X100690Y-1039935D01*
X101082Y-1040565D01*
X101395Y-1041300D01*
X101473Y-1042350D01*
X101395Y-1043400D01*
X101082Y-1044135D01*
X100690Y-1044765D01*
X100220Y-1045185D01*
X99593Y-1045500D01*
X98027D01*
G01X105110Y-1039200D02*
X106990D01*
G01X106050D02*
Y-1045500D01*
G01X105110D02*
X106990D01*
G01X110705Y-1044660D02*
X111332Y-1045185D01*
X112037Y-1045500D01*
X112663D01*
X113290Y-1045185D01*
X113760Y-1044660D01*
X113995Y-1043925D01*
X113838Y-1043190D01*
X113447Y-1042560D01*
X112742Y-1042140D01*
X111802Y-1041930D01*
X111253Y-1041510D01*
X111018Y-1040775D01*
X111175Y-1040040D01*
X111567Y-1039515D01*
X112115Y-1039200D01*
X112663D01*
X113212Y-1039410D01*
X113682Y-1039935D01*
G01X118650Y-1039200D02*
Y-1045500D01*
G01X116848Y-1039200D02*
X120452D01*
G01X124950Y-1045710D02*
X124793Y-1045605D01*
Y-1045395D01*
X124950Y-1045290D01*
X125107Y-1045395D01*
Y-1045605D01*
X124950Y-1045710D01*
G01X131093Y-1046655D02*
X131407Y-1045290D01*
G01X137550Y-1039200D02*
Y-1045500D01*
G01X135748Y-1039200D02*
X139352D01*
G01X141892Y-1045500D02*
X143850Y-1039200D01*
X145808Y-1045500D01*
G01X145103Y-1043295D02*
X142597D01*
G01X150150Y-1045500D02*
X149523Y-1045395D01*
X148975Y-1044975D01*
X148505Y-1044345D01*
X148192Y-1043610D01*
X148035Y-1042770D01*
Y-1041930D01*
X148192Y-1041090D01*
X148505Y-1040355D01*
X148975Y-1039725D01*
X149523Y-1039305D01*
X150150Y-1039200D01*
X150777Y-1039305D01*
X151325Y-1039725D01*
X151795Y-1040355D01*
X152108Y-1041090D01*
X152265Y-1041930D01*
Y-1042770D01*
X152108Y-1043610D01*
X151795Y-1044345D01*
X151325Y-1044975D01*
X150777Y-1045395D01*
X150150Y-1045500D01*
G01X156450D02*
Y-1042665D01*
X154883Y-1039200D01*
G01X158017D02*
X156450Y-1042665D01*
G01X161027Y-1039200D02*
Y-1043715D01*
X161340Y-1044660D01*
X161967Y-1045290D01*
X162750Y-1045500D01*
X163533Y-1045290D01*
X164160Y-1044660D01*
X164473Y-1043715D01*
Y-1039200D01*
G01X167092Y-1045500D02*
X169050Y-1039200D01*
X171008Y-1045500D01*
G01X170303Y-1043295D02*
X167797D01*
G01X173548Y-1045500D02*
Y-1039200D01*
X177152Y-1045500D01*
Y-1039200D01*
G01X51073Y-1049725D02*
X50603Y-1049410D01*
X50055Y-1049200D01*
X49428D01*
X48723Y-1049515D01*
X48175Y-1050040D01*
X47783Y-1050670D01*
X47470Y-1051720D01*
X47392Y-1052665D01*
X47548Y-1053610D01*
X47783Y-1054240D01*
X48253Y-1054870D01*
X48802Y-1055290D01*
X49350Y-1055500D01*
X49898D01*
X50447Y-1055290D01*
X50917Y-1054975D01*
X51308Y-1054555D01*
G01X54710Y-1049200D02*
X56590D01*
G01X55650D02*
Y-1055500D01*
G01X54710D02*
X56590D01*
G01X61950Y-1049200D02*
Y-1055500D01*
G01X60148Y-1049200D02*
X63752D01*
G01X68250Y-1055500D02*
Y-1052665D01*
X66683Y-1049200D01*
G01X69817D02*
X68250Y-1052665D01*
G01X79127Y-1054240D02*
X79597Y-1054975D01*
X80223Y-1055395D01*
X80928Y-1055500D01*
X81555Y-1055395D01*
X82182Y-1054870D01*
X82573Y-1054240D01*
X82652Y-1053610D01*
X82495Y-1052875D01*
X81947Y-1052350D01*
X81398Y-1052140D01*
X80693D01*
G01X81398D02*
X81868Y-1051825D01*
X82260Y-1051300D01*
X82417Y-1050670D01*
X82260Y-1050040D01*
X81868Y-1049515D01*
X81163Y-1049200D01*
X80458Y-1049305D01*
X79753Y-1049725D01*
G01X85427Y-1054240D02*
X85897Y-1054975D01*
X86523Y-1055395D01*
X87228Y-1055500D01*
X87855Y-1055395D01*
X88482Y-1054870D01*
X88873Y-1054240D01*
X88952Y-1053610D01*
X88795Y-1052875D01*
X88247Y-1052350D01*
X87698Y-1052140D01*
X86993D01*
G01X87698D02*
X88168Y-1051825D01*
X88560Y-1051300D01*
X88717Y-1050670D01*
X88560Y-1050040D01*
X88168Y-1049515D01*
X87463Y-1049200D01*
X86758Y-1049305D01*
X86053Y-1049725D01*
G01X91727Y-1054240D02*
X92197Y-1054975D01*
X92823Y-1055395D01*
X93528Y-1055500D01*
X94155Y-1055395D01*
X94782Y-1054870D01*
X95173Y-1054240D01*
X95252Y-1053610D01*
X95095Y-1052875D01*
X94547Y-1052350D01*
X93998Y-1052140D01*
X93293D01*
G01X93998D02*
X94468Y-1051825D01*
X94860Y-1051300D01*
X95017Y-1050670D01*
X94860Y-1050040D01*
X94468Y-1049515D01*
X93763Y-1049200D01*
X93058Y-1049305D01*
X92353Y-1049725D01*
G01X99593Y-1055500D02*
X99750Y-1054135D01*
X99985Y-1052980D01*
X100298Y-1051930D01*
X100690Y-1050775D01*
X101317Y-1049200D01*
X98183D01*
G01X105893Y-1055500D02*
X106050Y-1054135D01*
X106285Y-1052980D01*
X106598Y-1051930D01*
X106990Y-1050775D01*
X107617Y-1049200D01*
X104483D01*
G01X112193Y-1056655D02*
X112507Y-1055290D01*
G01X118650Y-1049200D02*
Y-1055500D01*
G01X116848Y-1049200D02*
X120452D01*
G01X122992Y-1055500D02*
X124950Y-1049200D01*
X126908Y-1055500D01*
G01X126203Y-1053295D02*
X123697D01*
G01X130310Y-1049200D02*
X132190D01*
G01X131250D02*
Y-1055500D01*
G01X130310D02*
X132190D01*
G01X135200Y-1049200D02*
X136297Y-1055500D01*
X137550Y-1049200D01*
X138803Y-1055500D01*
X139900Y-1049200D01*
G01X141892Y-1055500D02*
X143850Y-1049200D01*
X145808Y-1055500D01*
G01X145103Y-1053295D02*
X142597D01*
G01X148348Y-1055500D02*
Y-1049200D01*
X151952Y-1055500D01*
Y-1049200D01*
G01X162358Y-1057600D02*
X161575Y-1056550D01*
X161183Y-1055500D01*
Y-1051300D01*
X161575Y-1050250D01*
X162358Y-1049200D01*
G01X173783Y-1055500D02*
Y-1049200D01*
X175742D01*
X176368Y-1049515D01*
X176760Y-1049935D01*
X176917Y-1050775D01*
X176760Y-1051615D01*
X176290Y-1052140D01*
X175742Y-1052455D01*
X173783D01*
G01X175742D02*
X176917Y-1055500D01*
G01X181650Y-1055710D02*
X181493Y-1055605D01*
Y-1055395D01*
X181650Y-1055290D01*
X181807Y-1055395D01*
Y-1055605D01*
X181650Y-1055710D01*
G01X187950Y-1055500D02*
X187323Y-1055395D01*
X186775Y-1054975D01*
X186305Y-1054345D01*
X185992Y-1053610D01*
X185835Y-1052770D01*
Y-1051930D01*
X185992Y-1051090D01*
X186305Y-1050355D01*
X186775Y-1049725D01*
X187323Y-1049305D01*
X187950Y-1049200D01*
X188577Y-1049305D01*
X189125Y-1049725D01*
X189595Y-1050355D01*
X189908Y-1051090D01*
X190065Y-1051930D01*
Y-1052770D01*
X189908Y-1053610D01*
X189595Y-1054345D01*
X189125Y-1054975D01*
X188577Y-1055395D01*
X187950Y-1055500D01*
G01X194250Y-1055710D02*
X194093Y-1055605D01*
Y-1055395D01*
X194250Y-1055290D01*
X194407Y-1055395D01*
Y-1055605D01*
X194250Y-1055710D01*
G01X202273Y-1049725D02*
X201803Y-1049410D01*
X201255Y-1049200D01*
X200628D01*
X199923Y-1049515D01*
X199375Y-1050040D01*
X198983Y-1050670D01*
X198670Y-1051720D01*
X198592Y-1052665D01*
X198748Y-1053610D01*
X198983Y-1054240D01*
X199453Y-1054870D01*
X200002Y-1055290D01*
X200550Y-1055500D01*
X201098D01*
X201647Y-1055290D01*
X202117Y-1054975D01*
X202508Y-1054555D01*
G01X206850Y-1055710D02*
X206693Y-1055605D01*
Y-1055395D01*
X206850Y-1055290D01*
X207007Y-1055395D01*
Y-1055605D01*
X206850Y-1055710D01*
G01X213542Y-1057600D02*
X214325Y-1056550D01*
X214717Y-1055500D01*
Y-1051300D01*
X214325Y-1050250D01*
X213542Y-1049200D01*
G01X47548Y-1035500D02*
Y-1029200D01*
X51152Y-1035500D01*
Y-1029200D01*
G01X55650Y-1035500D02*
X55023Y-1035395D01*
X54475Y-1034975D01*
X54005Y-1034345D01*
X53692Y-1033610D01*
X53535Y-1032770D01*
Y-1031930D01*
X53692Y-1031090D01*
X54005Y-1030355D01*
X54475Y-1029725D01*
X55023Y-1029305D01*
X55650Y-1029200D01*
X56277Y-1029305D01*
X56825Y-1029725D01*
X57295Y-1030355D01*
X57608Y-1031090D01*
X57765Y-1031930D01*
Y-1032770D01*
X57608Y-1033610D01*
X57295Y-1034345D01*
X56825Y-1034975D01*
X56277Y-1035395D01*
X55650Y-1035500D01*
G01X61950Y-1035710D02*
X61793Y-1035605D01*
Y-1035395D01*
X61950Y-1035290D01*
X62107Y-1035395D01*
Y-1035605D01*
X61950Y-1035710D01*
G01X66762Y-1030250D02*
X67232Y-1029620D01*
X67780Y-1029305D01*
X68407Y-1029200D01*
X69190Y-1029410D01*
X69738Y-1029935D01*
X69895Y-1030565D01*
X69817Y-1031195D01*
X69503Y-1031720D01*
X67937Y-1032770D01*
X67232Y-1033505D01*
X66762Y-1034555D01*
X66605Y-1035500D01*
X69895D01*
G01X74550D02*
Y-1029200D01*
X73610Y-1030460D01*
G01Y-1035500D02*
X75490D01*
G01X80850D02*
Y-1029200D01*
X79910Y-1030460D01*
G01Y-1035500D02*
X81790D01*
G01X86993Y-1036655D02*
X87307Y-1035290D01*
G01X91100Y-1029200D02*
X92197Y-1035500D01*
X93450Y-1029200D01*
X94703Y-1035500D01*
X95800Y-1029200D01*
G01X101317Y-1035500D02*
X98183D01*
Y-1029200D01*
X101317D01*
G01X100063Y-1032245D02*
X98183D01*
G01X104248Y-1035500D02*
Y-1029200D01*
X107852Y-1035500D01*
Y-1029200D01*
G01X110705Y-1035500D02*
Y-1029200D01*
G01X113995D02*
Y-1035500D01*
G01Y-1032350D02*
X110705D01*
G01X116927Y-1029200D02*
Y-1033715D01*
X117240Y-1034660D01*
X117867Y-1035290D01*
X118650Y-1035500D01*
X119433Y-1035290D01*
X120060Y-1034660D01*
X120373Y-1033715D01*
Y-1029200D01*
G01X122992Y-1035500D02*
X124950Y-1029200D01*
X126908Y-1035500D01*
G01X126203Y-1033295D02*
X123697D01*
G01X136062Y-1030250D02*
X136532Y-1029620D01*
X137080Y-1029305D01*
X137707Y-1029200D01*
X138490Y-1029410D01*
X139038Y-1029935D01*
X139195Y-1030565D01*
X139117Y-1031195D01*
X138803Y-1031720D01*
X137237Y-1032770D01*
X136532Y-1033505D01*
X136062Y-1034555D01*
X135905Y-1035500D01*
X139195D01*
G01X142048D02*
Y-1029200D01*
X145652Y-1035500D01*
Y-1029200D01*
G01X148427Y-1035500D02*
Y-1029200D01*
X149993D01*
X150620Y-1029515D01*
X151090Y-1029935D01*
X151482Y-1030565D01*
X151795Y-1031300D01*
X151873Y-1032350D01*
X151795Y-1033400D01*
X151482Y-1034135D01*
X151090Y-1034765D01*
X150620Y-1035185D01*
X149993Y-1035500D01*
X148427D01*
G01X161183D02*
Y-1029200D01*
X163142D01*
X163768Y-1029515D01*
X164160Y-1029935D01*
X164317Y-1030775D01*
X164160Y-1031615D01*
X163690Y-1032140D01*
X163142Y-1032455D01*
X161183D01*
G01X163142D02*
X164317Y-1035500D01*
G01X167327D02*
Y-1029200D01*
X168893D01*
X169520Y-1029515D01*
X169990Y-1029935D01*
X170382Y-1030565D01*
X170695Y-1031300D01*
X170773Y-1032350D01*
X170695Y-1033400D01*
X170382Y-1034135D01*
X169990Y-1034765D01*
X169520Y-1035185D01*
X168893Y-1035500D01*
X167327D01*
G01X175350Y-1035710D02*
X175193Y-1035605D01*
Y-1035395D01*
X175350Y-1035290D01*
X175507Y-1035395D01*
Y-1035605D01*
X175350Y-1035710D01*
G01X256400Y-1037500D02*
Y-1029500D01*
X259000Y-1036167D01*
X261600Y-1029500D01*
Y-1037500D01*
G01X264500D02*
X267000Y-1029500D01*
X269500Y-1037500D01*
G01X268600Y-1034700D02*
X265400D01*
G01X272900Y-1036434D02*
X273700Y-1037100D01*
X274600Y-1037500D01*
X275400D01*
X276200Y-1037100D01*
X276800Y-1036434D01*
X277100Y-1035500D01*
X276900Y-1034567D01*
X276400Y-1033767D01*
X275500Y-1033233D01*
X274300Y-1032967D01*
X273600Y-1032433D01*
X273300Y-1031500D01*
X273500Y-1030567D01*
X274000Y-1029900D01*
X274700Y-1029500D01*
X275400D01*
X276100Y-1029767D01*
X276700Y-1030433D01*
G01X280800Y-1037500D02*
Y-1029500D01*
G01X284600D02*
X280800Y-1034434D01*
G01X285200Y-1037500D02*
X282500Y-1032167D01*
G01X289700Y-1034833D02*
X292300D01*
G01X299800Y-1033233D02*
X300200Y-1032833D01*
X300500Y-1032167D01*
X300700Y-1031233D01*
X300500Y-1030433D01*
X300100Y-1029900D01*
X299400Y-1029500D01*
X296700D01*
Y-1037500D01*
X300000D01*
X300700Y-1036967D01*
X301100Y-1036167D01*
X301300Y-1035233D01*
X301100Y-1034300D01*
X300500Y-1033500D01*
X299800Y-1033233D01*
X296700D01*
G01X307000Y-1037500D02*
X306200Y-1037367D01*
X305500Y-1036833D01*
X304900Y-1036033D01*
X304500Y-1035100D01*
X304300Y-1034033D01*
Y-1032967D01*
X304500Y-1031900D01*
X304900Y-1030967D01*
X305500Y-1030167D01*
X306200Y-1029633D01*
X307000Y-1029500D01*
X307800Y-1029633D01*
X308500Y-1030167D01*
X309100Y-1030967D01*
X309500Y-1031900D01*
X309700Y-1032967D01*
Y-1034033D01*
X309500Y-1035100D01*
X309100Y-1036033D01*
X308500Y-1036833D01*
X307800Y-1037367D01*
X307000Y-1037500D01*
G01X315000Y-1029500D02*
Y-1037500D01*
G01X312700Y-1029500D02*
X317300D01*
G01X243000Y-1004500D02*
Y-1012500D01*
X247000D01*
G01X254800D02*
Y-1007167D01*
G01Y-1008100D02*
X254400Y-1007567D01*
X253800Y-1007300D01*
X253100Y-1007167D01*
X252400Y-1007433D01*
X251800Y-1007967D01*
X251400Y-1008767D01*
X251200Y-1009833D01*
X251400Y-1010900D01*
X251800Y-1011700D01*
X252400Y-1012233D01*
X253100Y-1012500D01*
X253800Y-1012367D01*
X254400Y-1011967D01*
X254800Y-1011434D01*
G01X258900Y-1014900D02*
X259500Y-1015167D01*
X260300Y-1014900D01*
X260800Y-1014367D01*
X261200Y-1013700D01*
X261800Y-1011567D01*
X263100Y-1007167D01*
G01X259900D02*
X261800Y-1011567D01*
G01X267500Y-1008900D02*
X270700D01*
X270400Y-1007967D01*
X269900Y-1007433D01*
X269200Y-1007167D01*
X268500Y-1007300D01*
X267900Y-1007700D01*
X267500Y-1008633D01*
X267300Y-1009434D01*
Y-1010233D01*
X267500Y-1011033D01*
X268000Y-1011833D01*
X268600Y-1012367D01*
X269300Y-1012500D01*
X270000Y-1012233D01*
X270700Y-1011434D01*
G01X275600Y-1012500D02*
Y-1007167D01*
G01Y-1008233D02*
X276100Y-1007700D01*
X276600Y-1007300D01*
X277300Y-1007167D01*
X277800Y-1007300D01*
X278400Y-1007700D01*
G01X262100Y-1054500D02*
X265900D01*
X262100Y-1062500D01*
X265900D01*
G01X272000Y-1057167D02*
Y-1062500D01*
G01Y-1055033D02*
X271800Y-1054900D01*
Y-1054633D01*
X272000Y-1054500D01*
X272200Y-1054633D01*
Y-1054900D01*
X272000Y-1055033D01*
G01X278700Y-1059833D02*
X281300D01*
G01X286200Y-1065167D02*
Y-1057167D01*
G01Y-1058367D02*
X286700Y-1057700D01*
X287200Y-1057300D01*
X288000Y-1057167D01*
X288700Y-1057300D01*
X289400Y-1057967D01*
X289700Y-1058900D01*
X289800Y-1059833D01*
X289700Y-1060767D01*
X289400Y-1061700D01*
X288800Y-1062233D01*
X288000Y-1062500D01*
X287300Y-1062367D01*
X286600Y-1061967D01*
X286200Y-1061434D01*
G01X296000Y-1057167D02*
Y-1062500D01*
G01Y-1055033D02*
X295800Y-1054900D01*
Y-1054633D01*
X296000Y-1054500D01*
X296200Y-1054633D01*
Y-1054900D01*
X296000Y-1055033D01*
G01X302300Y-1062500D02*
Y-1057167D01*
G01Y-1058500D02*
X302700Y-1057833D01*
X303300Y-1057300D01*
X304100Y-1057167D01*
X304800Y-1057300D01*
X305400Y-1057833D01*
X305700Y-1058767D01*
Y-1062500D01*
G01X310600Y-1064500D02*
X311300Y-1065033D01*
X312100Y-1065167D01*
X312800Y-1065033D01*
X313400Y-1064367D01*
X313800Y-1063433D01*
Y-1057167D01*
G01Y-1058233D02*
X313400Y-1057700D01*
X312800Y-1057300D01*
X312100Y-1057167D01*
X311300Y-1057433D01*
X310800Y-1057967D01*
X310400Y-1058900D01*
X310200Y-1059833D01*
X310300Y-1060633D01*
X310700Y-1061567D01*
X311300Y-1062233D01*
X312100Y-1062500D01*
X312700Y-1062367D01*
X313400Y-1061833D01*
X313800Y-1061300D01*
G01X369600Y-1055833D02*
X370200Y-1055033D01*
X370900Y-1054633D01*
X371700Y-1054500D01*
X372700Y-1054767D01*
X373400Y-1055433D01*
X373600Y-1056233D01*
X373500Y-1057034D01*
X373100Y-1057700D01*
X371100Y-1059033D01*
X370200Y-1059967D01*
X369600Y-1061300D01*
X369400Y-1062500D01*
X373600D01*
G01X379500Y-1054500D02*
X378700Y-1054767D01*
X378100Y-1055433D01*
X377700Y-1056233D01*
X377400Y-1057300D01*
X377300Y-1058500D01*
X377400Y-1059700D01*
X377700Y-1060767D01*
X378100Y-1061567D01*
X378700Y-1062233D01*
X379500Y-1062500D01*
X380300Y-1062233D01*
X380900Y-1061567D01*
X381300Y-1060767D01*
X381600Y-1059700D01*
X381700Y-1058500D01*
X381600Y-1057300D01*
X381300Y-1056233D01*
X380900Y-1055433D01*
X380300Y-1054767D01*
X379500Y-1054500D01*
G01X385600Y-1055833D02*
X386200Y-1055033D01*
X386900Y-1054633D01*
X387700Y-1054500D01*
X388700Y-1054767D01*
X389400Y-1055433D01*
X389600Y-1056233D01*
X389500Y-1057034D01*
X389100Y-1057700D01*
X387100Y-1059033D01*
X386200Y-1059967D01*
X385600Y-1061300D01*
X385400Y-1062500D01*
X389600D01*
G01X393600Y-1055833D02*
X394200Y-1055033D01*
X394900Y-1054633D01*
X395700Y-1054500D01*
X396700Y-1054767D01*
X397400Y-1055433D01*
X397600Y-1056233D01*
X397500Y-1057034D01*
X397100Y-1057700D01*
X395100Y-1059033D01*
X394200Y-1059967D01*
X393600Y-1061300D01*
X393400Y-1062500D01*
X397600D01*
G01X401700Y-1062767D02*
X405300Y-1054500D01*
G01X411500Y-1062500D02*
Y-1054500D01*
X410300Y-1056100D01*
G01Y-1062500D02*
X412700D01*
G01X417600Y-1055833D02*
X418200Y-1055033D01*
X418900Y-1054633D01*
X419700Y-1054500D01*
X420700Y-1054767D01*
X421400Y-1055433D01*
X421600Y-1056233D01*
X421500Y-1057034D01*
X421100Y-1057700D01*
X419100Y-1059033D01*
X418200Y-1059967D01*
X417600Y-1061300D01*
X417400Y-1062500D01*
X421600D01*
G01X425700Y-1062767D02*
X429300Y-1054500D01*
G01X435500Y-1062500D02*
Y-1054500D01*
X434300Y-1056100D01*
G01Y-1062500D02*
X436700D01*
G01X441300Y-1060900D02*
X441900Y-1061833D01*
X442700Y-1062367D01*
X443600Y-1062500D01*
X444400Y-1062367D01*
X445200Y-1061700D01*
X445700Y-1060900D01*
X445800Y-1060100D01*
X445600Y-1059167D01*
X444900Y-1058500D01*
X444200Y-1058233D01*
X443300D01*
G01X444200D02*
X444800Y-1057833D01*
X445300Y-1057167D01*
X445500Y-1056367D01*
X445300Y-1055567D01*
X444800Y-1054900D01*
X443900Y-1054500D01*
X443000Y-1054633D01*
X442100Y-1055167D01*
G01X369300Y-1040000D02*
Y-1032000D01*
X371300D01*
X372100Y-1032400D01*
X372700Y-1032933D01*
X373200Y-1033733D01*
X373600Y-1034667D01*
X373700Y-1036000D01*
X373600Y-1037333D01*
X373200Y-1038267D01*
X372700Y-1039067D01*
X372100Y-1039600D01*
X371300Y-1040000D01*
X369300D01*
G01X377000D02*
X379500Y-1032000D01*
X382000Y-1040000D01*
G01X381100Y-1037200D02*
X377900D01*
G01X385600Y-1040000D02*
Y-1032000D01*
X389400D01*
G01X388000Y-1035867D02*
X385600D01*
G01X395500Y-1032000D02*
X394700Y-1032267D01*
X394100Y-1032933D01*
X393700Y-1033733D01*
X393400Y-1034800D01*
X393300Y-1036000D01*
X393400Y-1037200D01*
X393700Y-1038267D01*
X394100Y-1039067D01*
X394700Y-1039733D01*
X395500Y-1040000D01*
X396300Y-1039733D01*
X396900Y-1039067D01*
X397300Y-1038267D01*
X397600Y-1037200D01*
X397700Y-1036000D01*
X397600Y-1034800D01*
X397300Y-1033733D01*
X396900Y-1032933D01*
X396300Y-1032267D01*
X395500Y-1032000D01*
G01X403500D02*
Y-1040000D01*
G01X401200Y-1032000D02*
X405800D01*
G01X409500Y-1040000D02*
Y-1032000D01*
X411900D01*
X412700Y-1032400D01*
X413300Y-1033333D01*
X413500Y-1034400D01*
X413300Y-1035467D01*
X412800Y-1036267D01*
X411900Y-1036667D01*
X409500D01*
G01X420300Y-1035733D02*
X420700Y-1035333D01*
X421000Y-1034667D01*
X421200Y-1033733D01*
X421000Y-1032933D01*
X420600Y-1032400D01*
X419900Y-1032000D01*
X417200D01*
Y-1040000D01*
X420500D01*
X421200Y-1039467D01*
X421600Y-1038667D01*
X421800Y-1037733D01*
X421600Y-1036800D01*
X421000Y-1036000D01*
X420300Y-1035733D01*
X417200D01*
G01X427500Y-1040000D02*
Y-1032000D01*
X426300Y-1033600D01*
G01Y-1040000D02*
X428700D01*
G01X433000D02*
X435500Y-1032000D01*
X438000Y-1040000D01*
G01X437100Y-1037200D02*
X433900D01*
G01X441600Y-1040000D02*
Y-1032000D01*
X445400D01*
G01X444000Y-1035867D02*
X441600D01*
G01X451500Y-1032000D02*
X450700Y-1032267D01*
X450100Y-1032933D01*
X449700Y-1033733D01*
X449400Y-1034800D01*
X449300Y-1036000D01*
X449400Y-1037200D01*
X449700Y-1038267D01*
X450100Y-1039067D01*
X450700Y-1039733D01*
X451500Y-1040000D01*
X452300Y-1039733D01*
X452900Y-1039067D01*
X453300Y-1038267D01*
X453600Y-1037200D01*
X453700Y-1036000D01*
X453600Y-1034800D01*
X453300Y-1033733D01*
X452900Y-1032933D01*
X452300Y-1032267D01*
X451500Y-1032000D01*
G01X389600Y-1012500D02*
Y-1004500D01*
X393400D01*
G01X392000Y-1008367D02*
X389600D01*
G01X399500Y-1004500D02*
X398700Y-1004767D01*
X398100Y-1005433D01*
X397700Y-1006233D01*
X397400Y-1007300D01*
X397300Y-1008500D01*
X397400Y-1009700D01*
X397700Y-1010767D01*
X398100Y-1011567D01*
X398700Y-1012233D01*
X399500Y-1012500D01*
X400300Y-1012233D01*
X400900Y-1011567D01*
X401300Y-1010767D01*
X401600Y-1009700D01*
X401700Y-1008500D01*
X401600Y-1007300D01*
X401300Y-1006233D01*
X400900Y-1005433D01*
X400300Y-1004767D01*
X399500Y-1004500D01*
G01X407500D02*
Y-1012500D01*
G01X405200Y-1004500D02*
X409800D01*
G01X412500Y-1015167D02*
X418500D01*
G01X421500Y-1012500D02*
Y-1004500D01*
X423900D01*
X424700Y-1004900D01*
X425300Y-1005833D01*
X425500Y-1006900D01*
X425300Y-1007967D01*
X424800Y-1008767D01*
X423900Y-1009167D01*
X421500D01*
G01X429300Y-1012500D02*
Y-1004500D01*
X431300D01*
X432100Y-1004900D01*
X432700Y-1005433D01*
X433200Y-1006233D01*
X433600Y-1007167D01*
X433700Y-1008500D01*
X433600Y-1009833D01*
X433200Y-1010767D01*
X432700Y-1011567D01*
X432100Y-1012100D01*
X431300Y-1012500D01*
X429300D01*
G01X440300Y-1008233D02*
X440700Y-1007833D01*
X441000Y-1007167D01*
X441200Y-1006233D01*
X441000Y-1005433D01*
X440600Y-1004900D01*
X439900Y-1004500D01*
X437200D01*
Y-1012500D01*
X440500D01*
X441200Y-1011967D01*
X441600Y-1011167D01*
X441800Y-1010233D01*
X441600Y-1009300D01*
X441000Y-1008500D01*
X440300Y-1008233D01*
X437200D01*
G01X444500Y-1015167D02*
X450500D01*
G01X456300Y-1008233D02*
X456700Y-1007833D01*
X457000Y-1007167D01*
X457200Y-1006233D01*
X457000Y-1005433D01*
X456600Y-1004900D01*
X455900Y-1004500D01*
X453200D01*
Y-1012500D01*
X456500D01*
X457200Y-1011967D01*
X457600Y-1011167D01*
X457800Y-1010233D01*
X457600Y-1009300D01*
X457000Y-1008500D01*
X456300Y-1008233D01*
X453200D01*
G01X461300Y-1012500D02*
Y-1004500D01*
X463300D01*
X464100Y-1004900D01*
X464700Y-1005433D01*
X465200Y-1006233D01*
X465600Y-1007167D01*
X465700Y-1008500D01*
X465600Y-1009833D01*
X465200Y-1010767D01*
X464700Y-1011567D01*
X464100Y-1012100D01*
X463300Y-1012500D01*
X461300D01*
G01X468500Y-1015167D02*
X474500D01*
G01X480100Y-1008500D02*
X482100D01*
Y-1010900D01*
X481500Y-1011700D01*
X480800Y-1012233D01*
X479800Y-1012500D01*
X478800Y-1012233D01*
X478100Y-1011700D01*
X477500Y-1010900D01*
X477100Y-1009967D01*
X476900Y-1008900D01*
Y-1007967D01*
X477100Y-1007167D01*
X477500Y-1006233D01*
X478100Y-1005433D01*
X478700Y-1004900D01*
X479500Y-1004500D01*
X480200D01*
X481000Y-1004767D01*
X481600Y-1005300D01*
G01X485500Y-1012500D02*
Y-1004500D01*
X487900D01*
X488700Y-1004900D01*
X489300Y-1005833D01*
X489500Y-1006900D01*
X489300Y-1007967D01*
X488800Y-1008767D01*
X487900Y-1009167D01*
X485500D01*
G01X493300Y-1004500D02*
Y-1010233D01*
X493700Y-1011434D01*
X494500Y-1012233D01*
X495500Y-1012500D01*
X496500Y-1012233D01*
X497300Y-1011434D01*
X497700Y-1010233D01*
Y-1004500D01*
G01X458000Y-1065500D02*
Y-1057500D01*
X456800Y-1059100D01*
G01Y-1065500D02*
X459200D01*
G01X464100Y-1062167D02*
X464800Y-1061233D01*
X465400Y-1060700D01*
X466200Y-1060433D01*
X466900Y-1060700D01*
X467400Y-1061233D01*
X467800Y-1062033D01*
X467900Y-1062967D01*
X467800Y-1063767D01*
X467400Y-1064567D01*
X466800Y-1065233D01*
X466100Y-1065500D01*
X465300Y-1065233D01*
X464600Y-1064434D01*
X464200Y-1063233D01*
X464100Y-1061900D01*
X464300Y-1060167D01*
X464600Y-1059233D01*
X465100Y-1058300D01*
X465800Y-1057633D01*
X466500Y-1057500D01*
X467200Y-1057767D01*
X467700Y-1058433D01*
G01X474000Y-1065767D02*
X473800Y-1065633D01*
Y-1065367D01*
X474000Y-1065233D01*
X474200Y-1065367D01*
Y-1065633D01*
X474000Y-1065767D01*
G01X480100Y-1062167D02*
X480800Y-1061233D01*
X481400Y-1060700D01*
X482200Y-1060433D01*
X482900Y-1060700D01*
X483400Y-1061233D01*
X483800Y-1062033D01*
X483900Y-1062967D01*
X483800Y-1063767D01*
X483400Y-1064567D01*
X482800Y-1065233D01*
X482100Y-1065500D01*
X481300Y-1065233D01*
X480600Y-1064434D01*
X480200Y-1063233D01*
X480100Y-1061900D01*
X480300Y-1060167D01*
X480600Y-1059233D01*
X481100Y-1058300D01*
X481800Y-1057633D01*
X482500Y-1057500D01*
X483200Y-1057767D01*
X483700Y-1058433D01*
G01X503000Y-1065500D02*
Y-1057500D01*
X501800Y-1059100D01*
G01Y-1065500D02*
X504200D01*
G01X510800D02*
X511000Y-1063767D01*
X511300Y-1062300D01*
X511700Y-1060967D01*
X512200Y-1059500D01*
X513000Y-1057500D01*
X509000D01*
G01X519000Y-1065767D02*
X518800Y-1065633D01*
Y-1065367D01*
X519000Y-1065233D01*
X519200Y-1065367D01*
Y-1065633D01*
X519000Y-1065767D01*
G01X525100Y-1058833D02*
X525700Y-1058033D01*
X526400Y-1057633D01*
X527200Y-1057500D01*
X528200Y-1057767D01*
X528900Y-1058433D01*
X529100Y-1059233D01*
X529000Y-1060034D01*
X528600Y-1060700D01*
X526600Y-1062033D01*
X525700Y-1062967D01*
X525100Y-1064300D01*
X524900Y-1065500D01*
X529100D01*
G01X523100Y-1040500D02*
Y-1032500D01*
X526900D01*
G01X525500Y-1036367D02*
X523100D01*
G54D36*
X607668Y245500D03*
X608168Y302500D03*
X642168Y277500D03*
X631168Y282000D03*
X638168Y284500D03*
X642668Y298000D03*
Y293500D03*
X644584Y308500D03*
X671668Y269000D03*
X667668Y292500D03*
Y296500D03*
Y280500D03*
Y284500D03*
Y288500D03*
X667584Y308500D03*
X710484Y212000D03*
X695168Y251000D03*
X700668Y306500D03*
X696168Y302000D03*
X1027584Y208500D03*
X1073584Y245500D03*
X1097584Y247500D03*
Y251500D03*
X1099084Y297500D03*
Y289500D03*
X1101084Y285000D03*
X1099084Y293500D03*
X1127084Y263500D03*
Y278500D03*
Y283000D03*
Y287500D03*
Y292000D03*
X1629984Y146000D03*
Y142500D03*
Y153500D03*
X1664084Y138000D03*
X1680984Y149500D03*
X1738984Y181000D03*
Y186500D03*
X1769984Y184000D03*
G54D27*
X438100Y173117D03*
X612684Y311017D03*
X616684D03*
X635184Y293517D03*
Y301517D03*
X622184Y302517D03*
X1062600Y299517D03*
X1082100D03*
X1074100D03*
X1086100D03*
X1078100D03*
X1090100D03*
X1127100Y271517D03*
X1112500Y359017D03*
X1149600Y246517D03*
X1145600D03*
X1154600Y299517D03*
X1135000Y361017D03*
X1139000D03*
X1176000Y353517D03*
X1170500D03*
X1324100Y153517D03*
X1641077Y127521D03*
G54D63*
X1152155Y276000D03*
G54D45*
X638167Y269000D03*
Y264500D03*
Y260000D03*
Y273500D03*
Y288500D03*
X666167Y262500D03*
Y254500D03*
X664167Y267000D03*
X666167Y258500D03*
X667583Y304500D03*
Y300500D03*
X710483Y208000D03*
X691667Y306500D03*
X1027583Y212500D03*
X1064583Y245500D03*
X1069083Y250000D03*
X1070083Y301000D03*
X1097583Y259500D03*
Y255500D03*
Y267500D03*
Y263500D03*
Y243500D03*
Y271500D03*
X1093583Y283000D03*
X1120583Y243500D03*
X1127083Y267500D03*
X1122583Y258500D03*
Y254000D03*
X1123083Y274500D03*
X1134083Y270000D03*
X1157083Y249500D03*
X1157583Y306500D03*
X1165483Y338000D03*
X1629983Y139000D03*
Y149500D03*
X1655483Y138000D03*
X1680983Y141500D03*
Y145500D03*
Y153500D03*
G54D54*
X726100Y195008D03*
Y220992D03*
X752600Y195008D03*
Y220992D03*
X980500Y195008D03*
Y220992D03*
X1007000Y195008D03*
Y220992D03*
G54D18*
X166785Y200472D03*
Y280472D03*
Y360472D03*
Y440472D03*
Y520472D03*
X243785Y200472D03*
Y280472D03*
Y360472D03*
Y440472D03*
Y520472D03*
X1488500Y200472D03*
Y280472D03*
Y360472D03*
Y440472D03*
Y520472D03*
X1565500Y200472D03*
Y280472D03*
Y360472D03*
Y440472D03*
Y520472D03*
G54D37*
X604701Y245500D03*
X605201Y302500D03*
X639201Y277500D03*
X628201Y282000D03*
X635201Y284500D03*
X639701Y298000D03*
Y293500D03*
X641617Y308500D03*
X668701Y269000D03*
X664701Y292500D03*
Y296500D03*
Y280500D03*
Y284500D03*
Y288500D03*
X664617Y308500D03*
X707517Y212000D03*
X692201Y251000D03*
X697701Y306500D03*
X693201Y302000D03*
X1024617Y208500D03*
X1070617Y245500D03*
X1094617Y247500D03*
Y251500D03*
X1096117Y297500D03*
Y289500D03*
X1098117Y285000D03*
X1096117Y293500D03*
X1124117Y263500D03*
Y278500D03*
Y283000D03*
Y287500D03*
Y292000D03*
X1627017Y146000D03*
Y142500D03*
Y153500D03*
X1661117Y138000D03*
X1678017Y149500D03*
X1736017Y181000D03*
Y186500D03*
X1767017Y184000D03*
G54D55*
X729184Y285800D03*
Y274200D03*
X1033100Y266200D03*
Y277800D03*
X1055100Y301200D03*
Y312800D03*
G54D64*
X1157740Y337941D03*
Y343059D03*
X1150260D03*
Y340500D03*
Y337941D03*
G54D28*
X434100Y173116D03*
Y217516D03*
X438100D03*
X607684Y249516D03*
X612684Y302516D03*
X616684D03*
X635184Y277516D03*
X680100Y249516D03*
X676100D03*
X672184D03*
X688184D03*
X684184D03*
X699684D03*
X1127100Y255516D03*
Y247516D03*
X1149600Y238016D03*
X1145600D03*
X1140100Y246516D03*
X1163000Y344516D03*
X1328100Y153516D03*
X1324100Y197916D03*
X1328100D03*
X1645277Y127490D03*
G54D19*
X166785Y230000D03*
Y310000D03*
Y390000D03*
Y470000D03*
Y550000D03*
X243785Y230000D03*
Y310000D03*
Y390000D03*
Y470000D03*
Y550000D03*
X1488500Y230000D03*
Y310000D03*
Y390000D03*
Y470000D03*
Y550000D03*
X1565500Y230000D03*
Y310000D03*
Y390000D03*
Y470000D03*
Y550000D03*
G54D46*
X668314Y570042D03*
X681498Y575042D03*
Y565042D03*
X668420Y598187D03*
X681604Y593187D03*
Y603187D03*
X1011017Y570042D03*
X997833Y575042D03*
Y565042D03*
X1011017Y598187D03*
X997833Y593187D03*
Y603187D03*
G54D47*
X706600Y234799D03*
Y222201D03*
X1036600Y300701D03*
Y313299D03*
G54D65*
X1170941Y361260D03*
X1176059D03*
Y368740D03*
X1173500D03*
X1170941D03*
G54D29*
X434100Y176083D03*
Y220483D03*
X438100D03*
X607684Y252483D03*
X612684Y305483D03*
X616684D03*
X635184Y280483D03*
X680100Y252483D03*
X676100D03*
X672184D03*
X688184D03*
X684184D03*
X699684D03*
X1127100Y258483D03*
Y250483D03*
X1149600Y240983D03*
X1145600D03*
X1140100Y249483D03*
X1163000Y347483D03*
X1328100Y156483D03*
X1324100Y200883D03*
X1328100D03*
X1645277Y130457D03*
G54D56*
X802087Y145984D03*
X792087D03*
X802087Y135984D03*
X792087D03*
X802087Y180984D03*
X792087D03*
X802087Y170984D03*
X792087D03*
X802087Y200984D03*
X792087D03*
X802087Y230984D03*
X792087D03*
X802087Y220984D03*
X792087D03*
X802087Y265984D03*
X792087D03*
X802087Y255984D03*
X792087D03*
X822087Y145984D03*
X812087D03*
X822087Y135984D03*
X812087D03*
X822087Y180984D03*
X812087D03*
X822087Y170984D03*
X812087D03*
Y200984D03*
X822087Y230984D03*
X812087D03*
X822087Y220984D03*
X812087D03*
X822087Y265984D03*
X812087D03*
X822087Y255984D03*
X812087D03*
X920197Y145984D03*
X910197D03*
X920197Y135984D03*
X910197D03*
X920197Y180984D03*
X910197D03*
X920197Y170984D03*
X910197D03*
X920197Y200984D03*
X910197D03*
X920197Y230984D03*
X910197D03*
X920197Y220984D03*
X910197D03*
X920197Y265984D03*
X910197D03*
X920197Y255984D03*
X910197D03*
X940197Y145984D03*
X930197D03*
X940197Y135984D03*
X930197D03*
X940197Y180984D03*
X930197D03*
X940197Y170984D03*
X930197D03*
Y200984D03*
X940197Y230984D03*
X930197D03*
X940197Y220984D03*
X930197D03*
X940197Y265984D03*
X930197D03*
X940197Y255984D03*
X930197D03*
G54D38*
X610129Y276000D03*
G54D66*
X1643500Y147807D03*
Y145248D03*
Y173398D03*
Y170839D03*
Y168280D03*
Y165721D03*
Y163162D03*
Y160603D03*
Y158043D03*
Y155484D03*
Y152925D03*
Y150366D03*
X1666500Y145248D03*
Y147807D03*
Y150366D03*
Y152925D03*
Y155484D03*
Y158043D03*
Y160603D03*
Y163162D03*
Y165721D03*
Y168280D03*
Y170839D03*
Y173398D03*
G54D57*
X822087Y88484D03*
Y313484D03*
X940197Y88484D03*
Y313484D03*
G54D39*
X593198Y265173D03*
X620170D03*
Y286827D03*
X593198D03*
X1142114Y265173D03*
Y286827D03*
X1169086Y265173D03*
Y286827D03*
G54D48*
X691214Y278000D03*
X1071070Y274000D03*
G54D58*
X822087Y88484D03*
Y313484D03*
X940197Y88484D03*
Y313484D03*
G54D67*
X1848583Y99212D03*
X1848582Y481693D03*
G54D49*
X683134Y267170D03*
Y269140D03*
Y271110D03*
Y273080D03*
Y275050D03*
Y277020D03*
Y278980D03*
Y280950D03*
Y282920D03*
Y284890D03*
Y286860D03*
Y288830D03*
X714234Y269140D03*
Y267170D03*
Y288830D03*
Y286860D03*
Y284890D03*
Y282920D03*
Y280950D03*
Y278980D03*
Y277020D03*
Y275050D03*
Y273080D03*
Y271110D03*
X1048050Y263170D03*
Y265140D03*
Y267110D03*
Y269080D03*
Y271050D03*
Y273020D03*
Y274980D03*
Y276950D03*
Y278920D03*
Y280890D03*
Y282860D03*
Y284830D03*
X1079150Y269080D03*
Y267110D03*
Y265140D03*
Y263170D03*
Y284830D03*
Y282860D03*
Y280890D03*
Y278920D03*
Y276950D03*
Y274980D03*
Y273020D03*
Y271050D03*
G54D59*
X822087Y200984D03*
X940197D03*
G54D68*
X1835739Y99212D03*
X1835738Y481693D03*
G54D69*
X1846142Y230433D03*
Y240433D03*
X1856772D03*
Y230433D03*
X1846142Y250433D03*
Y260433D03*
Y270433D03*
X1856772D03*
Y260433D03*
Y250433D03*
X1846142Y280433D03*
Y290433D03*
Y300433D03*
X1856772D03*
Y290433D03*
Y280433D03*
X1848957Y324213D03*
X1843957Y329213D03*
X1848957Y314213D03*
X1843957Y319213D03*
X1853957Y329213D03*
Y319213D03*
X1858957Y324213D03*
Y314213D03*
X1848957Y334213D03*
Y344213D03*
X1843957Y339213D03*
Y349213D03*
X1853957D03*
Y339213D03*
X1858957Y344213D03*
Y334213D03*
M02*
